FILE_TYPE = MACRO_DRAWING;
SET COLOR_WIRE YELLOW;
SET COLOR_PROP ORANGE;
SET COLOR_DOT WHITE;
SET COLOR_ARC YELLOW;
SET COLOR_BODY GREEN;
SET COLOR_NOTE PURPLE;
SET PROP_DISPLAY VALUE;
SET PAGE_NUMBER P63;
FORCEADD TAP..1
R 2
(-600 1725);
FORCEPROP 3 LASTPIN (-550 1725) SIG_NAME UPI_CPU0_CPU1_P1P0_DN<0>
J 0
(-540 1735);
DISPLAY 0.659574 (-540 1735);
PAINT MONO (-540 1735);
DISPLAY INVISIBLE (-540 1735);
FORCEPROP 1 LASTPIN (-550 1725) BN 0
J 2
(-538 1733);
DISPLAY 0.680851 (-538 1733);
PAINT GREEN (-538 1733);
FORCEPROP 2 LAST CDS_LIB standard
J 0
(-600 1725);
DISPLAY INVISIBLE (-600 1725);
FORCEPROP 1 LAST BODY_TYPE PLUMBING
J 2
(-600 1775);
DISPLAY 0.872340 (-600 1775);
PAINT GREEN (-600 1775);
DISPLAY INVISIBLE (-600 1775);
FORCEPROP 1 LAST HDL_TAP TRUE
J 2
(-925 1600);
DISPLAY 0.872340 (-925 1600);
DISPLAY INVISIBLE (-925 1600);
FORCEPROP 1 LAST PATH I1
J 2
(-598 1725);
DISPLAY 0.872340 (-598 1725);
PAINT GREEN (-598 1725);
DISPLAY INVISIBLE (-598 1725);
FORCEADD TAP..1
R 2
(-600 2175);
FORCEPROP 3 LASTPIN (-550 2175) SIG_NAME UPI_CPU0_CPU1_P1P0_DN<9>
J 0
(-540 2185);
DISPLAY 0.659574 (-540 2185);
PAINT MONO (-540 2185);
DISPLAY INVISIBLE (-540 2185);
FORCEPROP 1 LASTPIN (-550 2175) BN 9
J 2
(-538 2183);
DISPLAY 0.680851 (-538 2183);
PAINT GREEN (-538 2183);
FORCEPROP 2 LAST CDS_LIB standard
J 0
(-600 2175);
DISPLAY INVISIBLE (-600 2175);
FORCEPROP 1 LAST BODY_TYPE PLUMBING
J 2
(-600 2225);
DISPLAY 0.872340 (-600 2225);
PAINT GREEN (-600 2225);
DISPLAY INVISIBLE (-600 2225);
FORCEPROP 1 LAST HDL_TAP TRUE
J 2
(-925 2050);
DISPLAY 0.872340 (-925 2050);
DISPLAY INVISIBLE (-925 2050);
FORCEPROP 1 LAST PATH I10
J 2
(-598 2175);
DISPLAY 0.872340 (-598 2175);
PAINT GREEN (-598 2175);
DISPLAY INVISIBLE (-598 2175);
FORCEADD OFFPAGE..2
(3975 2900);
FORCEPROP 2 LAST $XR0 33 
J 0
(4164 2900);
DISPLAY 0.638298 (4164 2900);
PAINT MONO (4164 2900);
FORCEPROP 2 LAST CDS_LIB standard
J 0
(3975 2900);
PAINT MONO (3975 2900);
DISPLAY INVISIBLE (3975 2900);
FORCEPROP 1 LAST OFFPAGE TRUE
J 0
(4300 2775);
DISPLAY 1.170213 (4300 2775);
PAINT GREEN (4300 2775);
DISPLAY INVISIBLE (4300 2775);
FORCEPROP 1 LAST COMMENT_BODY TRUE
J 0
(3930 2805);
DISPLAY 1.170213 (3930 2805);
PAINT GREEN (3930 2805);
DISPLAY INVISIBLE (3930 2805);
FORCEPROP 2 LAST PATH I100
J 0
(4150 2975);
DISPLAY 1.021277 (4150 2975);
DISPLAY INVISIBLE (4150 2975);
FORCEADD OFFPAGE..2
(3975 4150);
FORCEPROP 2 LAST $XR0 33 
J 0
(4164 4150);
DISPLAY 0.638298 (4164 4150);
PAINT MONO (4164 4150);
FORCEPROP 2 LAST CDS_LIB standard
J 0
(3975 4150);
PAINT MONO (3975 4150);
DISPLAY INVISIBLE (3975 4150);
FORCEPROP 1 LAST OFFPAGE TRUE
J 0
(4300 4025);
DISPLAY 1.170213 (4300 4025);
PAINT GREEN (4300 4025);
DISPLAY INVISIBLE (4300 4025);
FORCEPROP 1 LAST COMMENT_BODY TRUE
J 0
(3930 4055);
DISPLAY 1.170213 (3930 4055);
PAINT GREEN (3930 4055);
DISPLAY INVISIBLE (3930 4055);
FORCEPROP 2 LAST PATH I101
J 0
(4150 4225);
DISPLAY 1.021277 (4150 4225);
DISPLAY INVISIBLE (4150 4225);
FORCEADD TAP..1
R 2
(-600 2225);
FORCEPROP 3 LASTPIN (-550 2225) SIG_NAME UPI_CPU0_CPU1_P1P0_DN<10>
J 0
(-540 2235);
DISPLAY 0.659574 (-540 2235);
PAINT MONO (-540 2235);
DISPLAY INVISIBLE (-540 2235);
FORCEPROP 1 LASTPIN (-550 2225) BN 10
J 2
(-538 2233);
DISPLAY 0.680851 (-538 2233);
PAINT GREEN (-538 2233);
FORCEPROP 2 LAST CDS_LIB standard
J 0
(-600 2225);
DISPLAY INVISIBLE (-600 2225);
FORCEPROP 1 LAST BODY_TYPE PLUMBING
J 2
(-600 2275);
DISPLAY 0.872340 (-600 2275);
PAINT GREEN (-600 2275);
DISPLAY INVISIBLE (-600 2275);
FORCEPROP 1 LAST HDL_TAP TRUE
J 2
(-925 2100);
DISPLAY 0.872340 (-925 2100);
DISPLAY INVISIBLE (-925 2100);
FORCEPROP 1 LAST PATH I11
J 2
(-598 2225);
DISPLAY 0.872340 (-598 2225);
PAINT GREEN (-598 2225);
DISPLAY INVISIBLE (-598 2225);
FORCEADD TAP..1
R 2
(-600 2325);
FORCEPROP 3 LASTPIN (-550 2325) SIG_NAME UPI_CPU0_CPU1_P1P0_DN<12>
J 0
(-540 2335);
DISPLAY 0.659574 (-540 2335);
PAINT MONO (-540 2335);
DISPLAY INVISIBLE (-540 2335);
FORCEPROP 1 LASTPIN (-550 2325) BN 12
J 2
(-538 2333);
DISPLAY 0.680851 (-538 2333);
PAINT GREEN (-538 2333);
FORCEPROP 2 LAST CDS_LIB standard
J 0
(-600 2325);
DISPLAY INVISIBLE (-600 2325);
FORCEPROP 1 LAST BODY_TYPE PLUMBING
J 2
(-600 2375);
DISPLAY 0.872340 (-600 2375);
PAINT GREEN (-600 2375);
DISPLAY INVISIBLE (-600 2375);
FORCEPROP 1 LAST HDL_TAP TRUE
J 2
(-925 2200);
DISPLAY 0.872340 (-925 2200);
DISPLAY INVISIBLE (-925 2200);
FORCEPROP 1 LAST PATH I12
J 2
(-598 2325);
DISPLAY 0.872340 (-598 2325);
PAINT GREEN (-598 2325);
DISPLAY INVISIBLE (-598 2325);
FORCEADD TAP..1
R 2
(-600 2275);
FORCEPROP 3 LASTPIN (-550 2275) SIG_NAME UPI_CPU0_CPU1_P1P0_DN<11>
J 0
(-540 2285);
DISPLAY 0.659574 (-540 2285);
PAINT MONO (-540 2285);
DISPLAY INVISIBLE (-540 2285);
FORCEPROP 1 LASTPIN (-550 2275) BN 11
J 2
(-538 2283);
DISPLAY 0.680851 (-538 2283);
PAINT GREEN (-538 2283);
FORCEPROP 2 LAST CDS_LIB standard
J 0
(-600 2275);
DISPLAY INVISIBLE (-600 2275);
FORCEPROP 1 LAST BODY_TYPE PLUMBING
J 2
(-600 2325);
DISPLAY 0.872340 (-600 2325);
PAINT GREEN (-600 2325);
DISPLAY INVISIBLE (-600 2325);
FORCEPROP 1 LAST HDL_TAP TRUE
J 2
(-925 2150);
DISPLAY 0.872340 (-925 2150);
DISPLAY INVISIBLE (-925 2150);
FORCEPROP 1 LAST PATH I13
J 2
(-598 2275);
DISPLAY 0.872340 (-598 2275);
PAINT GREEN (-598 2275);
DISPLAY INVISIBLE (-598 2275);
FORCEADD TAP..1
R 2
(-600 2425);
FORCEPROP 3 LASTPIN (-550 2425) SIG_NAME UPI_CPU0_CPU1_P1P0_DN<14>
J 0
(-540 2435);
DISPLAY 0.659574 (-540 2435);
PAINT MONO (-540 2435);
DISPLAY INVISIBLE (-540 2435);
FORCEPROP 1 LASTPIN (-550 2425) BN 14
J 2
(-538 2433);
DISPLAY 0.680851 (-538 2433);
PAINT GREEN (-538 2433);
FORCEPROP 2 LAST CDS_LIB standard
J 0
(-600 2425);
DISPLAY INVISIBLE (-600 2425);
FORCEPROP 1 LAST BODY_TYPE PLUMBING
J 2
(-600 2475);
DISPLAY 0.872340 (-600 2475);
PAINT GREEN (-600 2475);
DISPLAY INVISIBLE (-600 2475);
FORCEPROP 1 LAST HDL_TAP TRUE
J 2
(-925 2300);
DISPLAY 0.872340 (-925 2300);
DISPLAY INVISIBLE (-925 2300);
FORCEPROP 1 LAST PATH I14
J 2
(-598 2425);
DISPLAY 0.872340 (-598 2425);
PAINT GREEN (-598 2425);
DISPLAY INVISIBLE (-598 2425);
FORCEADD TAP..1
R 2
(-600 2375);
FORCEPROP 3 LASTPIN (-550 2375) SIG_NAME UPI_CPU0_CPU1_P1P0_DN<13>
J 0
(-540 2385);
DISPLAY 0.659574 (-540 2385);
PAINT MONO (-540 2385);
DISPLAY INVISIBLE (-540 2385);
FORCEPROP 1 LASTPIN (-550 2375) BN 13
J 2
(-538 2383);
DISPLAY 0.680851 (-538 2383);
PAINT GREEN (-538 2383);
FORCEPROP 2 LAST CDS_LIB standard
J 0
(-600 2375);
DISPLAY INVISIBLE (-600 2375);
FORCEPROP 1 LAST BODY_TYPE PLUMBING
J 2
(-600 2425);
DISPLAY 0.872340 (-600 2425);
PAINT GREEN (-600 2425);
DISPLAY INVISIBLE (-600 2425);
FORCEPROP 1 LAST HDL_TAP TRUE
J 2
(-925 2250);
DISPLAY 0.872340 (-925 2250);
DISPLAY INVISIBLE (-925 2250);
FORCEPROP 1 LAST PATH I15
J 2
(-598 2375);
DISPLAY 0.872340 (-598 2375);
PAINT GREEN (-598 2375);
DISPLAY INVISIBLE (-598 2375);
FORCEADD TAP..1
R 2
(-600 2475);
FORCEPROP 3 LASTPIN (-550 2475) SIG_NAME UPI_CPU0_CPU1_P1P0_DN<15>
J 0
(-540 2485);
DISPLAY 0.659574 (-540 2485);
PAINT MONO (-540 2485);
DISPLAY INVISIBLE (-540 2485);
FORCEPROP 1 LASTPIN (-550 2475) BN 15
J 2
(-538 2483);
DISPLAY 0.680851 (-538 2483);
PAINT GREEN (-538 2483);
FORCEPROP 2 LAST CDS_LIB standard
J 0
(-600 2475);
DISPLAY INVISIBLE (-600 2475);
FORCEPROP 1 LAST BODY_TYPE PLUMBING
J 2
(-600 2525);
DISPLAY 0.872340 (-600 2525);
PAINT GREEN (-600 2525);
DISPLAY INVISIBLE (-600 2525);
FORCEPROP 1 LAST HDL_TAP TRUE
J 2
(-925 2350);
DISPLAY 0.872340 (-925 2350);
DISPLAY INVISIBLE (-925 2350);
FORCEPROP 1 LAST PATH I16
J 2
(-598 2475);
DISPLAY 0.872340 (-598 2475);
PAINT GREEN (-598 2475);
DISPLAY INVISIBLE (-598 2475);
FORCEADD OFFPAGE..1
(-1850 2900);
FORCEPROP 2 LAST $XR0 33 
J 0
(-2071 2900);
DISPLAY 0.638298 (-2071 2900);
PAINT MONO (-2071 2900);
FORCEPROP 2 LAST CDS_LIB standard
J 0
(-1850 2900);
PAINT MONO (-1850 2900);
DISPLAY INVISIBLE (-1850 2900);
FORCEPROP 1 LAST OFFPAGE TRUE
J 0
(-1525 2775);
DISPLAY 0.872340 (-1525 2775);
DISPLAY INVISIBLE (-1525 2775);
FORCEPROP 1 LAST COMMENT_BODY TRUE
J 0
(-1725 2800);
DISPLAY 0.872340 (-1725 2800);
PAINT GREEN (-1725 2800);
DISPLAY INVISIBLE (-1725 2800);
FORCEPROP 2 LAST PATH I17
J 0
(-1800 2975);
DISPLAY 1.021277 (-1800 2975);
DISPLAY INVISIBLE (-1800 2975);
FORCEADD OFFPAGE..1
(-1850 4150);
FORCEPROP 2 LAST $XR0 33 
J 0
(-2071 4150);
DISPLAY 0.638298 (-2071 4150);
PAINT MONO (-2071 4150);
FORCEPROP 2 LAST CDS_LIB standard
J 0
(-1850 4150);
PAINT MONO (-1850 4150);
DISPLAY INVISIBLE (-1850 4150);
FORCEPROP 1 LAST OFFPAGE TRUE
J 0
(-1525 4025);
DISPLAY 0.872340 (-1525 4025);
DISPLAY INVISIBLE (-1525 4025);
FORCEPROP 1 LAST COMMENT_BODY TRUE
J 0
(-1725 4050);
DISPLAY 0.872340 (-1725 4050);
PAINT GREEN (-1725 4050);
DISPLAY INVISIBLE (-1725 4050);
FORCEPROP 2 LAST PATH I18
J 0
(-1800 4225);
DISPLAY 1.021277 (-1800 4225);
DISPLAY INVISIBLE (-1800 4225);
FORCEADD TAP..1
R 2
(-600 2525);
FORCEPROP 3 LASTPIN (-550 2525) SIG_NAME UPI_CPU0_CPU1_P1P0_DN<16>
J 0
(-540 2535);
DISPLAY 0.659574 (-540 2535);
PAINT MONO (-540 2535);
DISPLAY INVISIBLE (-540 2535);
FORCEPROP 1 LASTPIN (-550 2525) BN 16
J 2
(-538 2533);
DISPLAY 0.680851 (-538 2533);
PAINT GREEN (-538 2533);
FORCEPROP 2 LAST CDS_LIB standard
J 0
(-600 2525);
PAINT MONO (-600 2525);
DISPLAY INVISIBLE (-600 2525);
FORCEPROP 1 LAST BODY_TYPE PLUMBING
J 2
(-600 2575);
DISPLAY 0.872340 (-600 2575);
PAINT GREEN (-600 2575);
DISPLAY INVISIBLE (-600 2575);
FORCEPROP 1 LAST HDL_TAP TRUE
J 2
(-925 2400);
DISPLAY 0.872340 (-925 2400);
DISPLAY INVISIBLE (-925 2400);
FORCEPROP 1 LAST PATH I19
J 2
(-598 2525);
DISPLAY 0.872340 (-598 2525);
PAINT GREEN (-598 2525);
DISPLAY INVISIBLE (-598 2525);
FORCEADD TAP..1
R 2
(-600 1775);
FORCEPROP 3 LASTPIN (-550 1775) SIG_NAME UPI_CPU0_CPU1_P1P0_DN<1>
J 0
(-540 1785);
DISPLAY 0.659574 (-540 1785);
PAINT MONO (-540 1785);
DISPLAY INVISIBLE (-540 1785);
FORCEPROP 1 LASTPIN (-550 1775) BN 1
J 2
(-538 1783);
DISPLAY 0.680851 (-538 1783);
PAINT GREEN (-538 1783);
FORCEPROP 2 LAST CDS_LIB standard
J 0
(-600 1775);
DISPLAY INVISIBLE (-600 1775);
FORCEPROP 1 LAST BODY_TYPE PLUMBING
J 2
(-600 1825);
DISPLAY 0.872340 (-600 1825);
PAINT GREEN (-600 1825);
DISPLAY INVISIBLE (-600 1825);
FORCEPROP 1 LAST HDL_TAP TRUE
J 2
(-925 1650);
DISPLAY 0.872340 (-925 1650);
DISPLAY INVISIBLE (-925 1650);
FORCEPROP 1 LAST PATH I2
J 2
(-598 1775);
DISPLAY 0.872340 (-598 1775);
PAINT GREEN (-598 1775);
DISPLAY INVISIBLE (-598 1775);
FORCEADD TAP..1
R 2
(-600 2575);
FORCEPROP 3 LASTPIN (-550 2575) SIG_NAME UPI_CPU0_CPU1_P1P0_DN<17>
J 0
(-540 2585);
DISPLAY 0.659574 (-540 2585);
PAINT MONO (-540 2585);
DISPLAY INVISIBLE (-540 2585);
FORCEPROP 1 LASTPIN (-550 2575) BN 17
J 2
(-538 2583);
DISPLAY 0.680851 (-538 2583);
PAINT GREEN (-538 2583);
FORCEPROP 2 LAST CDS_LIB standard
J 0
(-600 2575);
PAINT MONO (-600 2575);
DISPLAY INVISIBLE (-600 2575);
FORCEPROP 1 LAST BODY_TYPE PLUMBING
J 2
(-600 2625);
DISPLAY 0.872340 (-600 2625);
PAINT GREEN (-600 2625);
DISPLAY INVISIBLE (-600 2625);
FORCEPROP 1 LAST HDL_TAP TRUE
J 2
(-925 2450);
DISPLAY 0.872340 (-925 2450);
DISPLAY INVISIBLE (-925 2450);
FORCEPROP 1 LAST PATH I20
J 2
(-598 2575);
DISPLAY 0.872340 (-598 2575);
PAINT GREEN (-598 2575);
DISPLAY INVISIBLE (-598 2575);
FORCEADD TAP..1
R 2
(-600 2625);
FORCEPROP 3 LASTPIN (-550 2625) SIG_NAME UPI_CPU0_CPU1_P1P0_DN<18>
J 0
(-540 2635);
DISPLAY 0.659574 (-540 2635);
PAINT MONO (-540 2635);
DISPLAY INVISIBLE (-540 2635);
FORCEPROP 1 LASTPIN (-550 2625) BN 18
J 2
(-538 2633);
DISPLAY 0.680851 (-538 2633);
PAINT GREEN (-538 2633);
FORCEPROP 2 LAST CDS_LIB standard
J 0
(-600 2625);
PAINT MONO (-600 2625);
DISPLAY INVISIBLE (-600 2625);
FORCEPROP 1 LAST BODY_TYPE PLUMBING
J 2
(-600 2675);
DISPLAY 0.872340 (-600 2675);
PAINT GREEN (-600 2675);
DISPLAY INVISIBLE (-600 2675);
FORCEPROP 1 LAST HDL_TAP TRUE
J 2
(-925 2500);
DISPLAY 0.872340 (-925 2500);
DISPLAY INVISIBLE (-925 2500);
FORCEPROP 1 LAST PATH I21
J 2
(-598 2625);
DISPLAY 0.872340 (-598 2625);
PAINT GREEN (-598 2625);
DISPLAY INVISIBLE (-598 2625);
FORCEADD TAP..1
R 2
(-600 2725);
FORCEPROP 3 LASTPIN (-550 2725) SIG_NAME UPI_CPU0_CPU1_P1P0_DN<20>
J 0
(-540 2735);
DISPLAY 0.659574 (-540 2735);
PAINT MONO (-540 2735);
DISPLAY INVISIBLE (-540 2735);
FORCEPROP 1 LASTPIN (-550 2725) BN 20
J 2
(-538 2733);
DISPLAY 0.680851 (-538 2733);
PAINT GREEN (-538 2733);
FORCEPROP 2 LAST CDS_LIB standard
J 0
(-600 2725);
PAINT MONO (-600 2725);
DISPLAY INVISIBLE (-600 2725);
FORCEPROP 1 LAST BODY_TYPE PLUMBING
J 2
(-600 2775);
DISPLAY 0.872340 (-600 2775);
PAINT GREEN (-600 2775);
DISPLAY INVISIBLE (-600 2775);
FORCEPROP 1 LAST HDL_TAP TRUE
J 2
(-925 2600);
DISPLAY 0.872340 (-925 2600);
DISPLAY INVISIBLE (-925 2600);
FORCEPROP 1 LAST PATH I22
J 2
(-598 2725);
DISPLAY 0.872340 (-598 2725);
PAINT GREEN (-598 2725);
DISPLAY INVISIBLE (-598 2725);
FORCEADD TAP..1
R 2
(-600 2675);
FORCEPROP 3 LASTPIN (-550 2675) SIG_NAME UPI_CPU0_CPU1_P1P0_DN<19>
J 0
(-540 2685);
DISPLAY 0.659574 (-540 2685);
PAINT MONO (-540 2685);
DISPLAY INVISIBLE (-540 2685);
FORCEPROP 1 LASTPIN (-550 2675) BN 19
J 2
(-538 2683);
DISPLAY 0.680851 (-538 2683);
PAINT GREEN (-538 2683);
FORCEPROP 2 LAST CDS_LIB standard
J 0
(-600 2675);
PAINT MONO (-600 2675);
DISPLAY INVISIBLE (-600 2675);
FORCEPROP 1 LAST BODY_TYPE PLUMBING
J 2
(-600 2725);
DISPLAY 0.872340 (-600 2725);
PAINT GREEN (-600 2725);
DISPLAY INVISIBLE (-600 2725);
FORCEPROP 1 LAST HDL_TAP TRUE
J 2
(-925 2550);
DISPLAY 0.872340 (-925 2550);
DISPLAY INVISIBLE (-925 2550);
FORCEPROP 1 LAST PATH I23
J 2
(-598 2675);
DISPLAY 0.872340 (-598 2675);
PAINT GREEN (-598 2675);
DISPLAY INVISIBLE (-598 2675);
FORCEADD TAP..1
R 2
(-600 2775);
FORCEPROP 3 LASTPIN (-550 2775) SIG_NAME UPI_CPU0_CPU1_P1P0_DN<21>
J 0
(-540 2785);
DISPLAY 0.659574 (-540 2785);
PAINT MONO (-540 2785);
DISPLAY INVISIBLE (-540 2785);
FORCEPROP 1 LASTPIN (-550 2775) BN 21
J 2
(-538 2783);
DISPLAY 0.680851 (-538 2783);
PAINT GREEN (-538 2783);
FORCEPROP 2 LAST CDS_LIB standard
J 0
(-600 2775);
PAINT MONO (-600 2775);
DISPLAY INVISIBLE (-600 2775);
FORCEPROP 1 LAST BODY_TYPE PLUMBING
J 2
(-600 2825);
DISPLAY 0.872340 (-600 2825);
PAINT GREEN (-600 2825);
DISPLAY INVISIBLE (-600 2825);
FORCEPROP 1 LAST HDL_TAP TRUE
J 2
(-925 2650);
DISPLAY 0.872340 (-925 2650);
DISPLAY INVISIBLE (-925 2650);
FORCEPROP 1 LAST PATH I24
J 2
(-598 2775);
DISPLAY 0.872340 (-598 2775);
PAINT GREEN (-598 2775);
DISPLAY INVISIBLE (-598 2775);
FORCEADD TAP..1
R 2
(-600 2825);
FORCEPROP 3 LASTPIN (-550 2825) SIG_NAME UPI_CPU0_CPU1_P1P0_DN<22>
J 0
(-540 2835);
DISPLAY 0.659574 (-540 2835);
PAINT MONO (-540 2835);
DISPLAY INVISIBLE (-540 2835);
FORCEPROP 1 LASTPIN (-550 2825) BN 22
J 2
(-538 2833);
DISPLAY 0.680851 (-538 2833);
PAINT GREEN (-538 2833);
FORCEPROP 2 LAST CDS_LIB standard
J 0
(-600 2825);
PAINT MONO (-600 2825);
DISPLAY INVISIBLE (-600 2825);
FORCEPROP 1 LAST BODY_TYPE PLUMBING
J 2
(-600 2875);
DISPLAY 0.872340 (-600 2875);
PAINT GREEN (-600 2875);
DISPLAY INVISIBLE (-600 2875);
FORCEPROP 1 LAST HDL_TAP TRUE
J 2
(-925 2700);
DISPLAY 0.872340 (-925 2700);
DISPLAY INVISIBLE (-925 2700);
FORCEPROP 1 LAST PATH I25
J 2
(-598 2825);
DISPLAY 0.872340 (-598 2825);
PAINT GREEN (-598 2825);
DISPLAY INVISIBLE (-598 2825);
FORCEADD TAP..1
R 2
(-600 2875);
FORCEPROP 3 LASTPIN (-550 2875) SIG_NAME UPI_CPU0_CPU1_P1P0_DN<23>
J 0
(-540 2885);
DISPLAY 0.659574 (-540 2885);
PAINT MONO (-540 2885);
DISPLAY INVISIBLE (-540 2885);
FORCEPROP 1 LASTPIN (-550 2875) BN 23
J 2
(-538 2883);
DISPLAY 0.680851 (-538 2883);
PAINT GREEN (-538 2883);
FORCEPROP 2 LAST CDS_LIB standard
J 0
(-600 2875);
PAINT MONO (-600 2875);
DISPLAY INVISIBLE (-600 2875);
FORCEPROP 1 LAST BODY_TYPE PLUMBING
J 2
(-600 2925);
DISPLAY 0.872340 (-600 2925);
PAINT GREEN (-600 2925);
DISPLAY INVISIBLE (-600 2925);
FORCEPROP 1 LAST HDL_TAP TRUE
J 2
(-925 2750);
DISPLAY 0.872340 (-925 2750);
DISPLAY INVISIBLE (-925 2750);
FORCEPROP 1 LAST PATH I26
J 2
(-598 2875);
DISPLAY 0.872340 (-598 2875);
PAINT GREEN (-598 2875);
DISPLAY INVISIBLE (-598 2875);
FORCEADD TAP..1
R 2
(-600 2975);
FORCEPROP 3 LASTPIN (-550 2975) SIG_NAME UPI_CPU0_CPU1_P1P0_DP<0>
J 0
(-540 2985);
DISPLAY 0.659574 (-540 2985);
PAINT MONO (-540 2985);
DISPLAY INVISIBLE (-540 2985);
FORCEPROP 1 LASTPIN (-550 2975) BN 0
J 2
(-538 2983);
DISPLAY 0.680851 (-538 2983);
PAINT GREEN (-538 2983);
FORCEPROP 2 LAST CDS_LIB standard
J 0
(-600 2975);
DISPLAY INVISIBLE (-600 2975);
FORCEPROP 1 LAST BODY_TYPE PLUMBING
J 2
(-600 3025);
DISPLAY 0.872340 (-600 3025);
PAINT GREEN (-600 3025);
DISPLAY INVISIBLE (-600 3025);
FORCEPROP 1 LAST HDL_TAP TRUE
J 2
(-925 2850);
DISPLAY 0.872340 (-925 2850);
DISPLAY INVISIBLE (-925 2850);
FORCEPROP 1 LAST PATH I27
J 2
(-598 2975);
DISPLAY 0.872340 (-598 2975);
PAINT GREEN (-598 2975);
DISPLAY INVISIBLE (-598 2975);
FORCEADD TAP..1
R 2
(-600 3075);
FORCEPROP 3 LASTPIN (-550 3075) SIG_NAME UPI_CPU0_CPU1_P1P0_DP<2>
J 0
(-540 3085);
DISPLAY 0.659574 (-540 3085);
PAINT MONO (-540 3085);
DISPLAY INVISIBLE (-540 3085);
FORCEPROP 1 LASTPIN (-550 3075) BN 2
J 2
(-538 3083);
DISPLAY 0.680851 (-538 3083);
PAINT GREEN (-538 3083);
FORCEPROP 2 LAST CDS_LIB standard
J 0
(-600 3075);
DISPLAY INVISIBLE (-600 3075);
FORCEPROP 1 LAST BODY_TYPE PLUMBING
J 2
(-600 3125);
DISPLAY 0.872340 (-600 3125);
PAINT GREEN (-600 3125);
DISPLAY INVISIBLE (-600 3125);
FORCEPROP 1 LAST HDL_TAP TRUE
J 2
(-925 2950);
DISPLAY 0.872340 (-925 2950);
DISPLAY INVISIBLE (-925 2950);
FORCEPROP 1 LAST PATH I28
J 2
(-598 3075);
DISPLAY 0.872340 (-598 3075);
PAINT GREEN (-598 3075);
DISPLAY INVISIBLE (-598 3075);
FORCEADD TAP..1
R 2
(-600 3025);
FORCEPROP 3 LASTPIN (-550 3025) SIG_NAME UPI_CPU0_CPU1_P1P0_DP<1>
J 0
(-540 3035);
DISPLAY 0.659574 (-540 3035);
PAINT MONO (-540 3035);
DISPLAY INVISIBLE (-540 3035);
FORCEPROP 1 LASTPIN (-550 3025) BN 1
J 2
(-538 3033);
DISPLAY 0.680851 (-538 3033);
PAINT GREEN (-538 3033);
FORCEPROP 2 LAST CDS_LIB standard
J 0
(-600 3025);
DISPLAY INVISIBLE (-600 3025);
FORCEPROP 1 LAST BODY_TYPE PLUMBING
J 2
(-600 3075);
DISPLAY 0.872340 (-600 3075);
PAINT GREEN (-600 3075);
DISPLAY INVISIBLE (-600 3075);
FORCEPROP 1 LAST HDL_TAP TRUE
J 2
(-925 2900);
DISPLAY 0.872340 (-925 2900);
DISPLAY INVISIBLE (-925 2900);
FORCEPROP 1 LAST PATH I29
J 2
(-598 3025);
DISPLAY 0.872340 (-598 3025);
PAINT GREEN (-598 3025);
DISPLAY INVISIBLE (-598 3025);
FORCEADD TAP..1
R 2
(-600 1825);
FORCEPROP 3 LASTPIN (-550 1825) SIG_NAME UPI_CPU0_CPU1_P1P0_DN<2>
J 0
(-540 1835);
DISPLAY 0.659574 (-540 1835);
PAINT MONO (-540 1835);
DISPLAY INVISIBLE (-540 1835);
FORCEPROP 1 LASTPIN (-550 1825) BN 2
J 2
(-538 1833);
DISPLAY 0.680851 (-538 1833);
PAINT GREEN (-538 1833);
FORCEPROP 2 LAST CDS_LIB standard
J 0
(-600 1825);
DISPLAY INVISIBLE (-600 1825);
FORCEPROP 1 LAST BODY_TYPE PLUMBING
J 2
(-600 1875);
DISPLAY 0.872340 (-600 1875);
PAINT GREEN (-600 1875);
DISPLAY INVISIBLE (-600 1875);
FORCEPROP 1 LAST HDL_TAP TRUE
J 2
(-925 1700);
DISPLAY 0.872340 (-925 1700);
DISPLAY INVISIBLE (-925 1700);
FORCEPROP 1 LAST PATH I3
J 2
(-598 1825);
DISPLAY 0.872340 (-598 1825);
PAINT GREEN (-598 1825);
DISPLAY INVISIBLE (-598 1825);
FORCEADD TAP..1
R 2
(-600 3125);
FORCEPROP 3 LASTPIN (-550 3125) SIG_NAME UPI_CPU0_CPU1_P1P0_DP<3>
J 0
(-540 3135);
DISPLAY 0.659574 (-540 3135);
PAINT MONO (-540 3135);
DISPLAY INVISIBLE (-540 3135);
FORCEPROP 1 LASTPIN (-550 3125) BN 3
J 2
(-538 3133);
DISPLAY 0.680851 (-538 3133);
PAINT GREEN (-538 3133);
FORCEPROP 2 LAST CDS_LIB standard
J 0
(-600 3125);
DISPLAY INVISIBLE (-600 3125);
FORCEPROP 1 LAST BODY_TYPE PLUMBING
J 2
(-600 3175);
DISPLAY 0.872340 (-600 3175);
PAINT GREEN (-600 3175);
DISPLAY INVISIBLE (-600 3175);
FORCEPROP 1 LAST HDL_TAP TRUE
J 2
(-925 3000);
DISPLAY 0.872340 (-925 3000);
DISPLAY INVISIBLE (-925 3000);
FORCEPROP 1 LAST PATH I30
J 2
(-598 3125);
DISPLAY 0.872340 (-598 3125);
PAINT GREEN (-598 3125);
DISPLAY INVISIBLE (-598 3125);
FORCEADD TAP..1
R 2
(-600 3225);
FORCEPROP 3 LASTPIN (-550 3225) SIG_NAME UPI_CPU0_CPU1_P1P0_DP<5>
J 0
(-540 3235);
DISPLAY 0.659574 (-540 3235);
PAINT MONO (-540 3235);
DISPLAY INVISIBLE (-540 3235);
FORCEPROP 1 LASTPIN (-550 3225) BN 5
J 2
(-538 3233);
DISPLAY 0.680851 (-538 3233);
PAINT GREEN (-538 3233);
FORCEPROP 2 LAST CDS_LIB standard
J 0
(-600 3225);
DISPLAY INVISIBLE (-600 3225);
FORCEPROP 1 LAST BODY_TYPE PLUMBING
J 2
(-600 3275);
DISPLAY 0.872340 (-600 3275);
PAINT GREEN (-600 3275);
DISPLAY INVISIBLE (-600 3275);
FORCEPROP 1 LAST HDL_TAP TRUE
J 2
(-925 3100);
DISPLAY 0.872340 (-925 3100);
DISPLAY INVISIBLE (-925 3100);
FORCEPROP 1 LAST PATH I31
J 2
(-598 3225);
DISPLAY 0.872340 (-598 3225);
PAINT GREEN (-598 3225);
DISPLAY INVISIBLE (-598 3225);
FORCEADD TAP..1
R 2
(-600 3175);
FORCEPROP 3 LASTPIN (-550 3175) SIG_NAME UPI_CPU0_CPU1_P1P0_DP<4>
J 0
(-540 3185);
DISPLAY 0.659574 (-540 3185);
PAINT MONO (-540 3185);
DISPLAY INVISIBLE (-540 3185);
FORCEPROP 1 LASTPIN (-550 3175) BN 4
J 2
(-538 3183);
DISPLAY 0.680851 (-538 3183);
PAINT GREEN (-538 3183);
FORCEPROP 2 LAST CDS_LIB standard
J 0
(-600 3175);
DISPLAY INVISIBLE (-600 3175);
FORCEPROP 1 LAST BODY_TYPE PLUMBING
J 2
(-600 3225);
DISPLAY 0.872340 (-600 3225);
PAINT GREEN (-600 3225);
DISPLAY INVISIBLE (-600 3225);
FORCEPROP 1 LAST HDL_TAP TRUE
J 2
(-925 3050);
DISPLAY 0.872340 (-925 3050);
DISPLAY INVISIBLE (-925 3050);
FORCEPROP 1 LAST PATH I32
J 2
(-598 3175);
DISPLAY 0.872340 (-598 3175);
PAINT GREEN (-598 3175);
DISPLAY INVISIBLE (-598 3175);
FORCEADD TAP..1
R 2
(-600 3275);
FORCEPROP 3 LASTPIN (-550 3275) SIG_NAME UPI_CPU0_CPU1_P1P0_DP<6>
J 0
(-540 3285);
DISPLAY 0.659574 (-540 3285);
PAINT MONO (-540 3285);
DISPLAY INVISIBLE (-540 3285);
FORCEPROP 1 LASTPIN (-550 3275) BN 6
J 2
(-538 3283);
DISPLAY 0.680851 (-538 3283);
PAINT GREEN (-538 3283);
FORCEPROP 2 LAST CDS_LIB standard
J 0
(-600 3275);
DISPLAY INVISIBLE (-600 3275);
FORCEPROP 1 LAST BODY_TYPE PLUMBING
J 2
(-600 3325);
DISPLAY 0.872340 (-600 3325);
PAINT GREEN (-600 3325);
DISPLAY INVISIBLE (-600 3325);
FORCEPROP 1 LAST HDL_TAP TRUE
J 2
(-925 3150);
DISPLAY 0.872340 (-925 3150);
DISPLAY INVISIBLE (-925 3150);
FORCEPROP 1 LAST PATH I33
J 2
(-598 3275);
DISPLAY 0.872340 (-598 3275);
PAINT GREEN (-598 3275);
DISPLAY INVISIBLE (-598 3275);
FORCEADD TAP..1
R 2
(-600 3325);
FORCEPROP 3 LASTPIN (-550 3325) SIG_NAME UPI_CPU0_CPU1_P1P0_DP<7>
J 0
(-540 3335);
DISPLAY 0.659574 (-540 3335);
PAINT MONO (-540 3335);
DISPLAY INVISIBLE (-540 3335);
FORCEPROP 1 LASTPIN (-550 3325) BN 7
J 2
(-538 3333);
DISPLAY 0.680851 (-538 3333);
PAINT GREEN (-538 3333);
FORCEPROP 2 LAST CDS_LIB standard
J 0
(-600 3325);
DISPLAY INVISIBLE (-600 3325);
FORCEPROP 1 LAST BODY_TYPE PLUMBING
J 2
(-600 3375);
DISPLAY 0.872340 (-600 3375);
PAINT GREEN (-600 3375);
DISPLAY INVISIBLE (-600 3375);
FORCEPROP 1 LAST HDL_TAP TRUE
J 2
(-925 3200);
DISPLAY 0.872340 (-925 3200);
DISPLAY INVISIBLE (-925 3200);
FORCEPROP 1 LAST PATH I34
J 2
(-598 3325);
DISPLAY 0.872340 (-598 3325);
PAINT GREEN (-598 3325);
DISPLAY INVISIBLE (-598 3325);
FORCEADD TAP..1
R 2
(-600 3375);
FORCEPROP 3 LASTPIN (-550 3375) SIG_NAME UPI_CPU0_CPU1_P1P0_DP<8>
J 0
(-540 3385);
DISPLAY 0.659574 (-540 3385);
PAINT MONO (-540 3385);
DISPLAY INVISIBLE (-540 3385);
FORCEPROP 1 LASTPIN (-550 3375) BN 8
J 2
(-538 3383);
DISPLAY 0.680851 (-538 3383);
PAINT GREEN (-538 3383);
FORCEPROP 2 LAST CDS_LIB standard
J 0
(-600 3375);
DISPLAY INVISIBLE (-600 3375);
FORCEPROP 1 LAST BODY_TYPE PLUMBING
J 2
(-600 3425);
DISPLAY 0.872340 (-600 3425);
PAINT GREEN (-600 3425);
DISPLAY INVISIBLE (-600 3425);
FORCEPROP 1 LAST HDL_TAP TRUE
J 2
(-925 3250);
DISPLAY 0.872340 (-925 3250);
DISPLAY INVISIBLE (-925 3250);
FORCEPROP 1 LAST PATH I35
J 2
(-598 3375);
DISPLAY 0.872340 (-598 3375);
PAINT GREEN (-598 3375);
DISPLAY INVISIBLE (-598 3375);
FORCEADD TAP..1
R 2
(-600 3475);
FORCEPROP 3 LASTPIN (-550 3475) SIG_NAME UPI_CPU0_CPU1_P1P0_DP<10>
J 0
(-540 3485);
DISPLAY 0.659574 (-540 3485);
PAINT MONO (-540 3485);
DISPLAY INVISIBLE (-540 3485);
FORCEPROP 1 LASTPIN (-550 3475) BN 10
J 2
(-538 3483);
DISPLAY 0.680851 (-538 3483);
PAINT GREEN (-538 3483);
FORCEPROP 2 LAST CDS_LIB standard
J 0
(-600 3475);
DISPLAY INVISIBLE (-600 3475);
FORCEPROP 1 LAST BODY_TYPE PLUMBING
J 2
(-600 3525);
DISPLAY 0.872340 (-600 3525);
PAINT GREEN (-600 3525);
DISPLAY INVISIBLE (-600 3525);
FORCEPROP 1 LAST HDL_TAP TRUE
J 2
(-925 3350);
DISPLAY 0.872340 (-925 3350);
DISPLAY INVISIBLE (-925 3350);
FORCEPROP 1 LAST PATH I36
J 2
(-598 3475);
DISPLAY 0.872340 (-598 3475);
PAINT GREEN (-598 3475);
DISPLAY INVISIBLE (-598 3475);
FORCEADD TAP..1
R 2
(-600 3425);
FORCEPROP 3 LASTPIN (-550 3425) SIG_NAME UPI_CPU0_CPU1_P1P0_DP<9>
J 0
(-540 3435);
DISPLAY 0.659574 (-540 3435);
PAINT MONO (-540 3435);
DISPLAY INVISIBLE (-540 3435);
FORCEPROP 1 LASTPIN (-550 3425) BN 9
J 2
(-538 3433);
DISPLAY 0.680851 (-538 3433);
PAINT GREEN (-538 3433);
FORCEPROP 2 LAST CDS_LIB standard
J 0
(-600 3425);
DISPLAY INVISIBLE (-600 3425);
FORCEPROP 1 LAST BODY_TYPE PLUMBING
J 2
(-600 3475);
DISPLAY 0.872340 (-600 3475);
PAINT GREEN (-600 3475);
DISPLAY INVISIBLE (-600 3475);
FORCEPROP 1 LAST HDL_TAP TRUE
J 2
(-925 3300);
DISPLAY 0.872340 (-925 3300);
DISPLAY INVISIBLE (-925 3300);
FORCEPROP 1 LAST PATH I37
J 2
(-598 3425);
DISPLAY 0.872340 (-598 3425);
PAINT GREEN (-598 3425);
DISPLAY INVISIBLE (-598 3425);
FORCEADD TAP..1
R 2
(-600 3525);
FORCEPROP 3 LASTPIN (-550 3525) SIG_NAME UPI_CPU0_CPU1_P1P0_DP<11>
J 0
(-540 3535);
DISPLAY 0.659574 (-540 3535);
PAINT MONO (-540 3535);
DISPLAY INVISIBLE (-540 3535);
FORCEPROP 1 LASTPIN (-550 3525) BN 11
J 2
(-538 3533);
DISPLAY 0.680851 (-538 3533);
PAINT GREEN (-538 3533);
FORCEPROP 2 LAST CDS_LIB standard
J 0
(-600 3525);
DISPLAY INVISIBLE (-600 3525);
FORCEPROP 1 LAST BODY_TYPE PLUMBING
J 2
(-600 3575);
DISPLAY 0.872340 (-600 3575);
PAINT GREEN (-600 3575);
DISPLAY INVISIBLE (-600 3575);
FORCEPROP 1 LAST HDL_TAP TRUE
J 2
(-925 3400);
DISPLAY 0.872340 (-925 3400);
DISPLAY INVISIBLE (-925 3400);
FORCEPROP 1 LAST PATH I38
J 2
(-598 3525);
DISPLAY 0.872340 (-598 3525);
PAINT GREEN (-598 3525);
DISPLAY INVISIBLE (-598 3525);
FORCEADD TAP..1
R 2
(-600 3575);
FORCEPROP 3 LASTPIN (-550 3575) SIG_NAME UPI_CPU0_CPU1_P1P0_DP<12>
J 0
(-540 3585);
DISPLAY 0.659574 (-540 3585);
PAINT MONO (-540 3585);
DISPLAY INVISIBLE (-540 3585);
FORCEPROP 1 LASTPIN (-550 3575) BN 12
J 2
(-538 3583);
DISPLAY 0.680851 (-538 3583);
PAINT GREEN (-538 3583);
FORCEPROP 2 LAST CDS_LIB standard
J 0
(-600 3575);
DISPLAY INVISIBLE (-600 3575);
FORCEPROP 1 LAST BODY_TYPE PLUMBING
J 2
(-600 3625);
DISPLAY 0.872340 (-600 3625);
PAINT GREEN (-600 3625);
DISPLAY INVISIBLE (-600 3625);
FORCEPROP 1 LAST HDL_TAP TRUE
J 2
(-925 3450);
DISPLAY 0.872340 (-925 3450);
DISPLAY INVISIBLE (-925 3450);
FORCEPROP 1 LAST PATH I39
J 2
(-598 3575);
DISPLAY 0.872340 (-598 3575);
PAINT GREEN (-598 3575);
DISPLAY INVISIBLE (-598 3575);
FORCEADD TAP..1
R 2
(-600 1875);
FORCEPROP 3 LASTPIN (-550 1875) SIG_NAME UPI_CPU0_CPU1_P1P0_DN<3>
J 0
(-540 1885);
DISPLAY 0.659574 (-540 1885);
PAINT MONO (-540 1885);
DISPLAY INVISIBLE (-540 1885);
FORCEPROP 1 LASTPIN (-550 1875) BN 3
J 2
(-538 1883);
DISPLAY 0.680851 (-538 1883);
PAINT GREEN (-538 1883);
FORCEPROP 2 LAST CDS_LIB standard
J 0
(-600 1875);
DISPLAY INVISIBLE (-600 1875);
FORCEPROP 1 LAST BODY_TYPE PLUMBING
J 2
(-600 1925);
DISPLAY 0.872340 (-600 1925);
PAINT GREEN (-600 1925);
DISPLAY INVISIBLE (-600 1925);
FORCEPROP 1 LAST HDL_TAP TRUE
J 2
(-925 1750);
DISPLAY 0.872340 (-925 1750);
DISPLAY INVISIBLE (-925 1750);
FORCEPROP 1 LAST PATH I4
J 2
(-598 1875);
DISPLAY 0.872340 (-598 1875);
PAINT GREEN (-598 1875);
DISPLAY INVISIBLE (-598 1875);
FORCEADD TAP..1
R 2
(-600 3625);
FORCEPROP 3 LASTPIN (-550 3625) SIG_NAME UPI_CPU0_CPU1_P1P0_DP<13>
J 0
(-540 3635);
DISPLAY 0.659574 (-540 3635);
PAINT MONO (-540 3635);
DISPLAY INVISIBLE (-540 3635);
FORCEPROP 1 LASTPIN (-550 3625) BN 13
J 2
(-538 3633);
DISPLAY 0.680851 (-538 3633);
PAINT GREEN (-538 3633);
FORCEPROP 2 LAST CDS_LIB standard
J 0
(-600 3625);
DISPLAY INVISIBLE (-600 3625);
FORCEPROP 1 LAST BODY_TYPE PLUMBING
J 2
(-600 3675);
DISPLAY 0.872340 (-600 3675);
PAINT GREEN (-600 3675);
DISPLAY INVISIBLE (-600 3675);
FORCEPROP 1 LAST HDL_TAP TRUE
J 2
(-925 3500);
DISPLAY 0.872340 (-925 3500);
DISPLAY INVISIBLE (-925 3500);
FORCEPROP 1 LAST PATH I40
J 2
(-598 3625);
DISPLAY 0.872340 (-598 3625);
PAINT GREEN (-598 3625);
DISPLAY INVISIBLE (-598 3625);
FORCEADD TAP..1
R 2
(-600 3675);
FORCEPROP 3 LASTPIN (-550 3675) SIG_NAME UPI_CPU0_CPU1_P1P0_DP<14>
J 0
(-540 3685);
DISPLAY 0.659574 (-540 3685);
PAINT MONO (-540 3685);
DISPLAY INVISIBLE (-540 3685);
FORCEPROP 1 LASTPIN (-550 3675) BN 14
J 2
(-538 3683);
DISPLAY 0.680851 (-538 3683);
PAINT GREEN (-538 3683);
FORCEPROP 2 LAST CDS_LIB standard
J 0
(-600 3675);
DISPLAY INVISIBLE (-600 3675);
FORCEPROP 1 LAST BODY_TYPE PLUMBING
J 2
(-600 3725);
DISPLAY 0.872340 (-600 3725);
PAINT GREEN (-600 3725);
DISPLAY INVISIBLE (-600 3725);
FORCEPROP 1 LAST HDL_TAP TRUE
J 2
(-925 3550);
DISPLAY 0.872340 (-925 3550);
DISPLAY INVISIBLE (-925 3550);
FORCEPROP 1 LAST PATH I41
J 2
(-598 3675);
DISPLAY 0.872340 (-598 3675);
PAINT GREEN (-598 3675);
DISPLAY INVISIBLE (-598 3675);
FORCEADD TAP..1
R 2
(-600 3725);
FORCEPROP 3 LASTPIN (-550 3725) SIG_NAME UPI_CPU0_CPU1_P1P0_DP<15>
J 0
(-540 3735);
DISPLAY 0.659574 (-540 3735);
PAINT MONO (-540 3735);
DISPLAY INVISIBLE (-540 3735);
FORCEPROP 1 LASTPIN (-550 3725) BN 15
J 2
(-538 3733);
DISPLAY 0.680851 (-538 3733);
PAINT GREEN (-538 3733);
FORCEPROP 2 LAST CDS_LIB standard
J 0
(-600 3725);
DISPLAY INVISIBLE (-600 3725);
FORCEPROP 1 LAST BODY_TYPE PLUMBING
J 2
(-600 3775);
DISPLAY 0.872340 (-600 3775);
PAINT GREEN (-600 3775);
DISPLAY INVISIBLE (-600 3775);
FORCEPROP 1 LAST HDL_TAP TRUE
J 2
(-925 3600);
DISPLAY 0.872340 (-925 3600);
DISPLAY INVISIBLE (-925 3600);
FORCEPROP 1 LAST PATH I42
J 2
(-598 3725);
DISPLAY 0.872340 (-598 3725);
PAINT GREEN (-598 3725);
DISPLAY INVISIBLE (-598 3725);
FORCEADD TAP..1
R 2
(-600 3775);
FORCEPROP 3 LASTPIN (-550 3775) SIG_NAME UPI_CPU0_CPU1_P1P0_DP<16>
J 0
(-540 3785);
DISPLAY 0.659574 (-540 3785);
PAINT MONO (-540 3785);
DISPLAY INVISIBLE (-540 3785);
FORCEPROP 1 LASTPIN (-550 3775) BN 16
J 2
(-538 3783);
DISPLAY 0.680851 (-538 3783);
PAINT GREEN (-538 3783);
FORCEPROP 2 LAST CDS_LIB standard
J 0
(-600 3775);
DISPLAY INVISIBLE (-600 3775);
FORCEPROP 1 LAST BODY_TYPE PLUMBING
J 2
(-600 3825);
DISPLAY 0.872340 (-600 3825);
PAINT GREEN (-600 3825);
DISPLAY INVISIBLE (-600 3825);
FORCEPROP 1 LAST HDL_TAP TRUE
J 2
(-925 3650);
DISPLAY 0.872340 (-925 3650);
DISPLAY INVISIBLE (-925 3650);
FORCEPROP 1 LAST PATH I43
J 2
(-598 3775);
DISPLAY 0.872340 (-598 3775);
PAINT GREEN (-598 3775);
DISPLAY INVISIBLE (-598 3775);
FORCEADD TAP..1
R 2
(-600 3875);
FORCEPROP 3 LASTPIN (-550 3875) SIG_NAME UPI_CPU0_CPU1_P1P0_DP<18>
J 0
(-540 3885);
DISPLAY 0.659574 (-540 3885);
PAINT MONO (-540 3885);
DISPLAY INVISIBLE (-540 3885);
FORCEPROP 1 LASTPIN (-550 3875) BN 18
J 2
(-538 3883);
DISPLAY 0.680851 (-538 3883);
PAINT GREEN (-538 3883);
FORCEPROP 2 LAST CDS_LIB standard
J 0
(-600 3875);
DISPLAY INVISIBLE (-600 3875);
FORCEPROP 1 LAST BODY_TYPE PLUMBING
J 2
(-600 3925);
DISPLAY 0.872340 (-600 3925);
PAINT GREEN (-600 3925);
DISPLAY INVISIBLE (-600 3925);
FORCEPROP 1 LAST HDL_TAP TRUE
J 2
(-925 3750);
DISPLAY 0.872340 (-925 3750);
DISPLAY INVISIBLE (-925 3750);
FORCEPROP 1 LAST PATH I44
J 2
(-598 3875);
DISPLAY 0.872340 (-598 3875);
PAINT GREEN (-598 3875);
DISPLAY INVISIBLE (-598 3875);
FORCEADD TAP..1
R 2
(-600 3825);
FORCEPROP 3 LASTPIN (-550 3825) SIG_NAME UPI_CPU0_CPU1_P1P0_DP<17>
J 0
(-540 3835);
DISPLAY 0.659574 (-540 3835);
PAINT MONO (-540 3835);
DISPLAY INVISIBLE (-540 3835);
FORCEPROP 1 LASTPIN (-550 3825) BN 17
J 2
(-538 3833);
DISPLAY 0.680851 (-538 3833);
PAINT GREEN (-538 3833);
FORCEPROP 2 LAST CDS_LIB standard
J 0
(-600 3825);
DISPLAY INVISIBLE (-600 3825);
FORCEPROP 1 LAST BODY_TYPE PLUMBING
J 2
(-600 3875);
DISPLAY 0.872340 (-600 3875);
PAINT GREEN (-600 3875);
DISPLAY INVISIBLE (-600 3875);
FORCEPROP 1 LAST HDL_TAP TRUE
J 2
(-925 3700);
DISPLAY 0.872340 (-925 3700);
DISPLAY INVISIBLE (-925 3700);
FORCEPROP 1 LAST PATH I45
J 2
(-598 3825);
DISPLAY 0.872340 (-598 3825);
PAINT GREEN (-598 3825);
DISPLAY INVISIBLE (-598 3825);
FORCEADD TAP..1
R 2
(-600 3975);
FORCEPROP 3 LASTPIN (-550 3975) SIG_NAME UPI_CPU0_CPU1_P1P0_DP<20>
J 0
(-540 3985);
DISPLAY 0.659574 (-540 3985);
PAINT MONO (-540 3985);
DISPLAY INVISIBLE (-540 3985);
FORCEPROP 1 LASTPIN (-550 3975) BN 20
J 2
(-538 3983);
DISPLAY 0.680851 (-538 3983);
PAINT GREEN (-538 3983);
FORCEPROP 2 LAST CDS_LIB standard
J 0
(-600 3975);
DISPLAY INVISIBLE (-600 3975);
FORCEPROP 1 LAST BODY_TYPE PLUMBING
J 2
(-600 4025);
DISPLAY 0.872340 (-600 4025);
PAINT GREEN (-600 4025);
DISPLAY INVISIBLE (-600 4025);
FORCEPROP 1 LAST HDL_TAP TRUE
J 2
(-925 3850);
DISPLAY 0.872340 (-925 3850);
DISPLAY INVISIBLE (-925 3850);
FORCEPROP 1 LAST PATH I46
J 2
(-598 3975);
DISPLAY 0.872340 (-598 3975);
PAINT GREEN (-598 3975);
DISPLAY INVISIBLE (-598 3975);
FORCEADD TAP..1
R 2
(-600 3925);
FORCEPROP 3 LASTPIN (-550 3925) SIG_NAME UPI_CPU0_CPU1_P1P0_DP<19>
J 0
(-540 3935);
DISPLAY 0.659574 (-540 3935);
PAINT MONO (-540 3935);
DISPLAY INVISIBLE (-540 3935);
FORCEPROP 1 LASTPIN (-550 3925) BN 19
J 2
(-538 3933);
DISPLAY 0.680851 (-538 3933);
PAINT GREEN (-538 3933);
FORCEPROP 2 LAST CDS_LIB standard
J 0
(-600 3925);
DISPLAY INVISIBLE (-600 3925);
FORCEPROP 1 LAST BODY_TYPE PLUMBING
J 2
(-600 3975);
DISPLAY 0.872340 (-600 3975);
PAINT GREEN (-600 3975);
DISPLAY INVISIBLE (-600 3975);
FORCEPROP 1 LAST HDL_TAP TRUE
J 2
(-925 3800);
DISPLAY 0.872340 (-925 3800);
DISPLAY INVISIBLE (-925 3800);
FORCEPROP 1 LAST PATH I47
J 2
(-598 3925);
DISPLAY 0.872340 (-598 3925);
PAINT GREEN (-598 3925);
DISPLAY INVISIBLE (-598 3925);
FORCEADD TAP..1
R 2
(-600 4025);
FORCEPROP 3 LASTPIN (-550 4025) SIG_NAME UPI_CPU0_CPU1_P1P0_DP<21>
J 0
(-540 4035);
DISPLAY 0.659574 (-540 4035);
PAINT MONO (-540 4035);
DISPLAY INVISIBLE (-540 4035);
FORCEPROP 1 LASTPIN (-550 4025) BN 21
J 2
(-538 4033);
DISPLAY 0.680851 (-538 4033);
PAINT GREEN (-538 4033);
FORCEPROP 2 LAST CDS_LIB standard
J 0
(-600 4025);
DISPLAY INVISIBLE (-600 4025);
FORCEPROP 1 LAST BODY_TYPE PLUMBING
J 2
(-600 4075);
DISPLAY 0.872340 (-600 4075);
PAINT GREEN (-600 4075);
DISPLAY INVISIBLE (-600 4075);
FORCEPROP 1 LAST HDL_TAP TRUE
J 2
(-925 3900);
DISPLAY 0.872340 (-925 3900);
DISPLAY INVISIBLE (-925 3900);
FORCEPROP 1 LAST PATH I48
J 2
(-598 4025);
DISPLAY 0.872340 (-598 4025);
PAINT GREEN (-598 4025);
DISPLAY INVISIBLE (-598 4025);
FORCEADD TAP..1
R 2
(-600 4075);
FORCEPROP 3 LASTPIN (-550 4075) SIG_NAME UPI_CPU0_CPU1_P1P0_DP<22>
J 0
(-540 4085);
DISPLAY 0.659574 (-540 4085);
PAINT MONO (-540 4085);
DISPLAY INVISIBLE (-540 4085);
FORCEPROP 1 LASTPIN (-550 4075) BN 22
J 2
(-538 4083);
DISPLAY 0.680851 (-538 4083);
PAINT GREEN (-538 4083);
FORCEPROP 2 LAST CDS_LIB standard
J 0
(-600 4075);
DISPLAY INVISIBLE (-600 4075);
FORCEPROP 1 LAST BODY_TYPE PLUMBING
J 2
(-600 4125);
DISPLAY 0.872340 (-600 4125);
PAINT GREEN (-600 4125);
DISPLAY INVISIBLE (-600 4125);
FORCEPROP 1 LAST HDL_TAP TRUE
J 2
(-925 3950);
DISPLAY 0.872340 (-925 3950);
DISPLAY INVISIBLE (-925 3950);
FORCEPROP 1 LAST PATH I49
J 2
(-598 4075);
DISPLAY 0.872340 (-598 4075);
PAINT GREEN (-598 4075);
DISPLAY INVISIBLE (-598 4075);
FORCEADD TAP..1
R 2
(-600 1925);
FORCEPROP 3 LASTPIN (-550 1925) SIG_NAME UPI_CPU0_CPU1_P1P0_DN<4>
J 0
(-540 1935);
DISPLAY 0.659574 (-540 1935);
PAINT MONO (-540 1935);
DISPLAY INVISIBLE (-540 1935);
FORCEPROP 1 LASTPIN (-550 1925) BN 4
J 2
(-538 1933);
DISPLAY 0.680851 (-538 1933);
PAINT GREEN (-538 1933);
FORCEPROP 2 LAST CDS_LIB standard
J 0
(-600 1925);
DISPLAY INVISIBLE (-600 1925);
FORCEPROP 1 LAST BODY_TYPE PLUMBING
J 2
(-600 1975);
DISPLAY 0.872340 (-600 1975);
PAINT GREEN (-600 1975);
DISPLAY INVISIBLE (-600 1975);
FORCEPROP 1 LAST HDL_TAP TRUE
J 2
(-925 1800);
DISPLAY 0.872340 (-925 1800);
DISPLAY INVISIBLE (-925 1800);
FORCEPROP 1 LAST PATH I5
J 2
(-598 1925);
DISPLAY 0.872340 (-598 1925);
PAINT GREEN (-598 1925);
DISPLAY INVISIBLE (-598 1925);
FORCEADD TAP..1
R 2
(-600 4125);
FORCEPROP 3 LASTPIN (-550 4125) SIG_NAME UPI_CPU0_CPU1_P1P0_DP<23>
J 0
(-540 4135);
DISPLAY 0.659574 (-540 4135);
PAINT MONO (-540 4135);
DISPLAY INVISIBLE (-540 4135);
FORCEPROP 1 LASTPIN (-550 4125) BN 23
J 2
(-538 4133);
DISPLAY 0.680851 (-538 4133);
PAINT GREEN (-538 4133);
FORCEPROP 2 LAST CDS_LIB standard
J 0
(-600 4125);
DISPLAY INVISIBLE (-600 4125);
FORCEPROP 1 LAST BODY_TYPE PLUMBING
J 2
(-600 4175);
DISPLAY 0.872340 (-600 4175);
PAINT GREEN (-600 4175);
DISPLAY INVISIBLE (-600 4175);
FORCEPROP 1 LAST HDL_TAP TRUE
J 2
(-925 4000);
DISPLAY 0.872340 (-925 4000);
DISPLAY INVISIBLE (-925 4000);
FORCEPROP 1 LAST PATH I50
J 2
(-598 4125);
DISPLAY 0.872340 (-598 4125);
PAINT GREEN (-598 4125);
DISPLAY INVISIBLE (-598 4125);
FORCEADD SOCKET4677_AZIF0045P001C01CS..22
(1100 2925);
FORCEPROP 1 LAST PART_NUMBER DGA^7000023
J 0
(50 4375);
DISPLAY 0.723404 (50 4375);
PAINT GREEN (50 4375);
DISPLAY INVISIBLE (50 4375);
FORCEPROP 2 LAST VALUE SOCKET4677_AZIF0045-P001C01CS
J 0
(50 4500);
DISPLAY 1.021277 (50 4500);
FORCEPROP 1 LAST MATERIAL IO
J 0
(50 4300);
DISPLAY 0.723404 (50 4300);
PAINT GREEN (50 4300);
FORCEPROP 2 LAST PART_TYPE SMLF
J 0
(50 4550);
DISPLAY 1.021277 (50 4550);
FORCEPROP 1 LAST $LOCATION U1
J 0
(50 4450);
DISPLAY 0.723404 (50 4450);
PAINT GREEN (50 4450);
FORCEPROP 0 LASTPIN (-100 1725) $PN K6
J 2
(-110 1735);
DISPLAY 0.680851 (-110 1735);
PAINT MONO (-110 1735);
FORCEPROP 0 LASTPIN (-100 1775) $PN N5
J 2
(-110 1785);
DISPLAY 0.680851 (-110 1785);
PAINT MONO (-110 1785);
FORCEPROP 0 LASTPIN (-100 1825) $PN P6
J 2
(-110 1835);
DISPLAY 0.680851 (-110 1835);
PAINT MONO (-110 1835);
FORCEPROP 0 LASTPIN (-100 1875) $PN U5
J 2
(-110 1885);
DISPLAY 0.680851 (-110 1885);
PAINT MONO (-110 1885);
FORCEPROP 0 LASTPIN (-100 1925) $PN V6
J 2
(-110 1935);
DISPLAY 0.680851 (-110 1935);
PAINT MONO (-110 1935);
FORCEPROP 0 LASTPIN (-100 1975) $PN AA5
J 2
(-110 1985);
DISPLAY 0.680851 (-110 1985);
PAINT MONO (-110 1985);
FORCEPROP 0 LASTPIN (-100 2025) $PN AB6
J 2
(-110 2035);
DISPLAY 0.680851 (-110 2035);
PAINT MONO (-110 2035);
FORCEPROP 0 LASTPIN (-100 2075) $PN AE5
J 2
(-110 2085);
DISPLAY 0.680851 (-110 2085);
PAINT MONO (-110 2085);
FORCEPROP 0 LASTPIN (-100 2125) $PN AF6
J 2
(-110 2135);
DISPLAY 0.680851 (-110 2135);
PAINT MONO (-110 2135);
FORCEPROP 0 LASTPIN (-100 2175) $PN AH6
J 2
(-110 2185);
DISPLAY 0.680851 (-110 2185);
PAINT MONO (-110 2185);
FORCEPROP 0 LASTPIN (-100 2225) $PN AK6
J 2
(-110 2235);
DISPLAY 0.680851 (-110 2235);
PAINT MONO (-110 2235);
FORCEPROP 0 LASTPIN (-100 2275) $PN AN5
J 2
(-110 2285);
DISPLAY 0.680851 (-110 2285);
PAINT MONO (-110 2285);
FORCEPROP 0 LASTPIN (-100 2325) $PN AP6
J 2
(-110 2335);
DISPLAY 0.680851 (-110 2335);
PAINT MONO (-110 2335);
FORCEPROP 0 LASTPIN (-100 2375) $PN AU5
J 2
(-110 2385);
DISPLAY 0.680851 (-110 2385);
PAINT MONO (-110 2385);
FORCEPROP 0 LASTPIN (-100 2425) $PN AV6
J 2
(-110 2435);
DISPLAY 0.680851 (-110 2435);
PAINT MONO (-110 2435);
FORCEPROP 0 LASTPIN (-100 2475) $PN BA5
J 2
(-110 2485);
DISPLAY 0.680851 (-110 2485);
PAINT MONO (-110 2485);
FORCEPROP 0 LASTPIN (-100 2525) $PN BB6
J 2
(-110 2535);
DISPLAY 0.680851 (-110 2535);
PAINT MONO (-110 2535);
FORCEPROP 0 LASTPIN (-100 2575) $PN BE5
J 2
(-110 2585);
DISPLAY 0.680851 (-110 2585);
PAINT MONO (-110 2585);
FORCEPROP 0 LASTPIN (-100 2625) $PN BF6
J 2
(-110 2635);
DISPLAY 0.680851 (-110 2635);
PAINT MONO (-110 2635);
FORCEPROP 0 LASTPIN (-100 2675) $PN BJ5
J 2
(-110 2685);
DISPLAY 0.680851 (-110 2685);
PAINT MONO (-110 2685);
FORCEPROP 0 LASTPIN (-100 2725) $PN BK6
J 2
(-110 2735);
DISPLAY 0.680851 (-110 2735);
PAINT MONO (-110 2735);
FORCEPROP 0 LASTPIN (-100 2775) $PN BN5
J 2
(-110 2785);
DISPLAY 0.680851 (-110 2785);
PAINT MONO (-110 2785);
FORCEPROP 0 LASTPIN (-100 2825) $PN BR7
J 2
(-110 2835);
DISPLAY 0.680851 (-110 2835);
PAINT MONO (-110 2835);
FORCEPROP 0 LASTPIN (-100 2875) $PN BU5
J 2
(-110 2885);
DISPLAY 0.680851 (-110 2885);
PAINT MONO (-110 2885);
FORCEPROP 0 LASTPIN (-100 2975) $PN L7
J 2
(-110 2985);
DISPLAY 0.680851 (-110 2985);
PAINT MONO (-110 2985);
FORCEPROP 0 LASTPIN (-100 3025) $PN M6
J 2
(-110 3035);
DISPLAY 0.680851 (-110 3035);
PAINT MONO (-110 3035);
FORCEPROP 0 LASTPIN (-100 3075) $PN R7
J 2
(-110 3085);
DISPLAY 0.680851 (-110 3085);
PAINT MONO (-110 3085);
FORCEPROP 0 LASTPIN (-100 3125) $PN T6
J 2
(-110 3135);
DISPLAY 0.680851 (-110 3135);
PAINT MONO (-110 3135);
FORCEPROP 0 LASTPIN (-100 3175) $PN W7
J 2
(-110 3185);
DISPLAY 0.680851 (-110 3185);
PAINT MONO (-110 3185);
FORCEPROP 0 LASTPIN (-100 3225) $PN Y6
J 2
(-110 3235);
DISPLAY 0.680851 (-110 3235);
PAINT MONO (-110 3235);
FORCEPROP 0 LASTPIN (-100 3275) $PN AC7
J 2
(-110 3285);
DISPLAY 0.680851 (-110 3285);
PAINT MONO (-110 3285);
FORCEPROP 0 LASTPIN (-100 3325) $PN AD6
J 2
(-110 3335);
DISPLAY 0.680851 (-110 3335);
PAINT MONO (-110 3335);
FORCEPROP 0 LASTPIN (-100 3375) $PN AG7
J 2
(-110 3385);
DISPLAY 0.680851 (-110 3385);
PAINT MONO (-110 3385);
FORCEPROP 0 LASTPIN (-100 3425) $PN AJ5
J 2
(-110 3435);
DISPLAY 0.680851 (-110 3435);
PAINT MONO (-110 3435);
FORCEPROP 0 LASTPIN (-100 3475) $PN AL7
J 2
(-110 3485);
DISPLAY 0.680851 (-110 3485);
PAINT MONO (-110 3485);
FORCEPROP 0 LASTPIN (-100 3525) $PN AM6
J 2
(-110 3535);
DISPLAY 0.680851 (-110 3535);
PAINT MONO (-110 3535);
FORCEPROP 0 LASTPIN (-100 3575) $PN AR7
J 2
(-110 3585);
DISPLAY 0.680851 (-110 3585);
PAINT MONO (-110 3585);
FORCEPROP 0 LASTPIN (-100 3625) $PN AT6
J 2
(-110 3635);
DISPLAY 0.680851 (-110 3635);
PAINT MONO (-110 3635);
FORCEPROP 0 LASTPIN (-100 3675) $PN AW7
J 2
(-110 3685);
DISPLAY 0.680851 (-110 3685);
PAINT MONO (-110 3685);
FORCEPROP 0 LASTPIN (-100 3725) $PN AY6
J 2
(-110 3735);
DISPLAY 0.680851 (-110 3735);
PAINT MONO (-110 3735);
FORCEPROP 0 LASTPIN (-100 3775) $PN BC7
J 2
(-110 3785);
DISPLAY 0.680851 (-110 3785);
PAINT MONO (-110 3785);
FORCEPROP 0 LASTPIN (-100 3825) $PN BD6
J 2
(-110 3835);
DISPLAY 0.680851 (-110 3835);
PAINT MONO (-110 3835);
FORCEPROP 0 LASTPIN (-100 3875) $PN BG7
J 2
(-110 3885);
DISPLAY 0.680851 (-110 3885);
PAINT MONO (-110 3885);
FORCEPROP 0 LASTPIN (-100 3925) $PN BH6
J 2
(-110 3935);
DISPLAY 0.680851 (-110 3935);
PAINT MONO (-110 3935);
FORCEPROP 0 LASTPIN (-100 3975) $PN BL7
J 2
(-110 3985);
DISPLAY 0.680851 (-110 3985);
PAINT MONO (-110 3985);
FORCEPROP 0 LASTPIN (-100 4025) $PN BM6
J 2
(-110 4035);
DISPLAY 0.680851 (-110 4035);
PAINT MONO (-110 4035);
FORCEPROP 0 LASTPIN (-100 4075) $PN BP6
J 2
(-110 4085);
DISPLAY 0.680851 (-110 4085);
PAINT MONO (-110 4085);
FORCEPROP 0 LASTPIN (-100 4125) $PN BT6
J 2
(-110 4135);
DISPLAY 0.680851 (-110 4135);
PAINT MONO (-110 4135);
FORCEPROP 0 LASTPIN (2300 1725) $PN K4
J 0
(2310 1735);
DISPLAY 0.680851 (2310 1735);
PAINT MONO (2310 1735);
FORCEPROP 0 LASTPIN (2300 1775) $PN M2
J 0
(2310 1785);
DISPLAY 0.680851 (2310 1785);
PAINT MONO (2310 1785);
FORCEPROP 0 LASTPIN (2300 1825) $PN N1
J 0
(2310 1835);
DISPLAY 0.680851 (2310 1835);
PAINT MONO (2310 1835);
FORCEPROP 0 LASTPIN (2300 1875) $PN T2
J 0
(2310 1885);
DISPLAY 0.680851 (2310 1885);
PAINT MONO (2310 1885);
FORCEPROP 0 LASTPIN (2300 1925) $PN U1
J 0
(2310 1935);
DISPLAY 0.680851 (2310 1935);
PAINT MONO (2310 1935);
FORCEPROP 0 LASTPIN (2300 1975) $PN Y2
J 0
(2310 1985);
DISPLAY 0.680851 (2310 1985);
PAINT MONO (2310 1985);
FORCEPROP 0 LASTPIN (2300 2025) $PN AA1
J 0
(2310 2035);
DISPLAY 0.680851 (2310 2035);
PAINT MONO (2310 2035);
FORCEPROP 0 LASTPIN (2300 2075) $PN AD2
J 0
(2310 2085);
DISPLAY 0.680851 (2310 2085);
PAINT MONO (2310 2085);
FORCEPROP 0 LASTPIN (2300 2125) $PN AF2
J 0
(2310 2135);
DISPLAY 0.680851 (2310 2135);
PAINT MONO (2310 2135);
FORCEPROP 0 LASTPIN (2300 2175) $PN AH2
J 0
(2310 2185);
DISPLAY 0.680851 (2310 2185);
PAINT MONO (2310 2185);
FORCEPROP 0 LASTPIN (2300 2225) $PN AK2
J 0
(2310 2235);
DISPLAY 0.680851 (2310 2235);
PAINT MONO (2310 2235);
FORCEPROP 0 LASTPIN (2300 2275) $PN AM2
J 0
(2310 2285);
DISPLAY 0.680851 (2310 2285);
PAINT MONO (2310 2285);
FORCEPROP 0 LASTPIN (2300 2325) $PN AP2
J 0
(2310 2335);
DISPLAY 0.680851 (2310 2335);
PAINT MONO (2310 2335);
FORCEPROP 0 LASTPIN (2300 2375) $PN AT2
J 0
(2310 2385);
DISPLAY 0.680851 (2310 2385);
PAINT MONO (2310 2385);
FORCEPROP 0 LASTPIN (2300 2425) $PN AU1
J 0
(2310 2435);
DISPLAY 0.680851 (2310 2435);
PAINT MONO (2310 2435);
FORCEPROP 0 LASTPIN (2300 2475) $PN AY2
J 0
(2310 2485);
DISPLAY 0.680851 (2310 2485);
PAINT MONO (2310 2485);
FORCEPROP 0 LASTPIN (2300 2525) $PN BB2
J 0
(2310 2535);
DISPLAY 0.680851 (2310 2535);
PAINT MONO (2310 2535);
FORCEPROP 0 LASTPIN (2300 2575) $PN BD2
J 0
(2310 2585);
DISPLAY 0.680851 (2310 2585);
PAINT MONO (2310 2585);
FORCEPROP 0 LASTPIN (2300 2625) $PN BF2
J 0
(2310 2635);
DISPLAY 0.680851 (2310 2635);
PAINT MONO (2310 2635);
FORCEPROP 0 LASTPIN (2300 2675) $PN BH2
J 0
(2310 2685);
DISPLAY 0.680851 (2310 2685);
PAINT MONO (2310 2685);
FORCEPROP 0 LASTPIN (2300 2725) $PN BK2
J 0
(2310 2735);
DISPLAY 0.680851 (2310 2735);
PAINT MONO (2310 2735);
FORCEPROP 0 LASTPIN (2300 2775) $PN BM2
J 0
(2310 2785);
DISPLAY 0.680851 (2310 2785);
PAINT MONO (2310 2785);
FORCEPROP 0 LASTPIN (2300 2825) $PN BR3
J 0
(2310 2835);
DISPLAY 0.680851 (2310 2835);
PAINT MONO (2310 2835);
FORCEPROP 0 LASTPIN (2300 2875) $PN BT2
J 0
(2310 2885);
DISPLAY 0.680851 (2310 2885);
PAINT MONO (2310 2885);
FORCEPROP 0 LASTPIN (2300 2975) $PN J3
J 0
(2310 2985);
DISPLAY 0.680851 (2310 2985);
PAINT MONO (2310 2985);
FORCEPROP 0 LASTPIN (2300 3025) $PN L3
J 0
(2310 3035);
DISPLAY 0.680851 (2310 3035);
PAINT MONO (2310 3035);
FORCEPROP 0 LASTPIN (2300 3075) $PN P2
J 0
(2310 3085);
DISPLAY 0.680851 (2310 3085);
PAINT MONO (2310 3085);
FORCEPROP 0 LASTPIN (2300 3125) $PN R3
J 0
(2310 3135);
DISPLAY 0.680851 (2310 3135);
PAINT MONO (2310 3135);
FORCEPROP 0 LASTPIN (2300 3175) $PN V2
J 0
(2310 3185);
DISPLAY 0.680851 (2310 3185);
PAINT MONO (2310 3185);
FORCEPROP 0 LASTPIN (2300 3225) $PN W3
J 0
(2310 3235);
DISPLAY 0.680851 (2310 3235);
PAINT MONO (2310 3235);
FORCEPROP 0 LASTPIN (2300 3275) $PN AB2
J 0
(2310 3285);
DISPLAY 0.680851 (2310 3285);
PAINT MONO (2310 3285);
FORCEPROP 0 LASTPIN (2300 3325) $PN AC3
J 0
(2310 3335);
DISPLAY 0.680851 (2310 3335);
PAINT MONO (2310 3335);
FORCEPROP 0 LASTPIN (2300 3375) $PN AE1
J 0
(2310 3385);
DISPLAY 0.680851 (2310 3385);
PAINT MONO (2310 3385);
FORCEPROP 0 LASTPIN (2300 3425) $PN AG3
J 0
(2310 3435);
DISPLAY 0.680851 (2310 3435);
PAINT MONO (2310 3435);
FORCEPROP 0 LASTPIN (2300 3475) $PN AJ1
J 0
(2310 3485);
DISPLAY 0.680851 (2310 3485);
PAINT MONO (2310 3485);
FORCEPROP 0 LASTPIN (2300 3525) $PN AL3
J 0
(2310 3535);
DISPLAY 0.680851 (2310 3535);
PAINT MONO (2310 3535);
FORCEPROP 0 LASTPIN (2300 3575) $PN AN1
J 0
(2310 3585);
DISPLAY 0.680851 (2310 3585);
PAINT MONO (2310 3585);
FORCEPROP 0 LASTPIN (2300 3625) $PN AR3
J 0
(2310 3635);
DISPLAY 0.680851 (2310 3635);
PAINT MONO (2310 3635);
FORCEPROP 0 LASTPIN (2300 3675) $PN AV2
J 0
(2310 3685);
DISPLAY 0.680851 (2310 3685);
PAINT MONO (2310 3685);
FORCEPROP 0 LASTPIN (2300 3725) $PN AW3
J 0
(2310 3735);
DISPLAY 0.680851 (2310 3735);
PAINT MONO (2310 3735);
FORCEPROP 0 LASTPIN (2300 3775) $PN BA1
J 0
(2310 3785);
DISPLAY 0.680851 (2310 3785);
PAINT MONO (2310 3785);
FORCEPROP 0 LASTPIN (2300 3825) $PN BC3
J 0
(2310 3835);
DISPLAY 0.680851 (2310 3835);
PAINT MONO (2310 3835);
FORCEPROP 0 LASTPIN (2300 3875) $PN BE1
J 0
(2310 3885);
DISPLAY 0.680851 (2310 3885);
PAINT MONO (2310 3885);
FORCEPROP 0 LASTPIN (2300 3925) $PN BG3
J 0
(2310 3935);
DISPLAY 0.680851 (2310 3935);
PAINT MONO (2310 3935);
FORCEPROP 0 LASTPIN (2300 3975) $PN BJ1
J 0
(2310 3985);
DISPLAY 0.680851 (2310 3985);
PAINT MONO (2310 3985);
FORCEPROP 0 LASTPIN (2300 4025) $PN BL3
J 0
(2310 4035);
DISPLAY 0.680851 (2310 4035);
PAINT MONO (2310 4035);
FORCEPROP 0 LASTPIN (2300 4075) $PN BN3
J 0
(2310 4085);
DISPLAY 0.680851 (2310 4085);
PAINT MONO (2310 4085);
FORCEPROP 0 LASTPIN (2300 4125) $PN BU3
J 0
(2310 4135);
DISPLAY 0.680851 (2310 4135);
PAINT MONO (2310 4135);
FORCEPROP 1 LAST CDS_LMAN_SYM_OUTLINE -1050,1350,1050,-1350
J 0
(1100 2925);
DISPLAY 0.468085 (1100 2925);
PAINT GREEN (1100 2925);
DISPLAY INVISIBLE (1100 2925);
FORCEPROP 1 LAST NEEDS_NO_SIZE TRUE
J 0
(1100 2925);
DISPLAY 0.723404 (1100 2925);
PAINT GREEN (1100 2925);
DISPLAY INVISIBLE (1100 2925);
FORCEPROP 2 LAST CDS_LIB pure_quanta
J 0
(1100 2925);
DISPLAY INVISIBLE (1100 2925);
FORCEPROP 2 LAST CDS_LOCATION U1
J 0
(50 4600);
DISPLAY 1.021277 (50 4600);
DISPLAY INVISIBLE (50 4600);
FORCEPROP 0 LAST $SEC 22
J 0
(50 4600);
DISPLAY 0.680851 (50 4600);
PAINT MONO (50 4600);
DISPLAY INVISIBLE (50 4600);
FORCEPROP 2 LAST CDS_SEC 22
J 0
(50 4600);
DISPLAY 1.021277 (50 4600);
DISPLAY INVISIBLE (50 4600);
FORCEPROP 1 LAST PATH I51
J 0
(1100 2925);
DISPLAY 0.723404 (1100 2925);
PAINT GREEN (1100 2925);
DISPLAY INVISIBLE (1100 2925);
FORCEADD TAP..1
(2775 1725);
FORCEPROP 3 LASTPIN (2725 1725) SIG_NAME UPI_CPU1_CPU0_P0P1_DN<0>
J 0
(2735 1735);
DISPLAY 0.659574 (2735 1735);
PAINT MONO (2735 1735);
DISPLAY INVISIBLE (2735 1735);
FORCEPROP 1 LASTPIN (2725 1725) BN 0
J 0
(2713 1733);
DISPLAY 0.680851 (2713 1733);
PAINT GREEN (2713 1733);
FORCEPROP 2 LAST CDS_LIB standard
J 0
(2775 1725);
PAINT MONO (2775 1725);
DISPLAY INVISIBLE (2775 1725);
FORCEPROP 1 LAST BODY_TYPE PLUMBING
J 0
(2775 1775);
DISPLAY 0.872340 (2775 1775);
PAINT GREEN (2775 1775);
DISPLAY INVISIBLE (2775 1775);
FORCEPROP 1 LAST HDL_TAP TRUE
J 0
(3100 1600);
DISPLAY 0.872340 (3100 1600);
DISPLAY INVISIBLE (3100 1600);
FORCEPROP 1 LAST PATH I52
J 0
(2773 1725);
DISPLAY 0.872340 (2773 1725);
PAINT GREEN (2773 1725);
DISPLAY INVISIBLE (2773 1725);
FORCEADD TAP..1
(2775 1775);
FORCEPROP 3 LASTPIN (2725 1775) SIG_NAME UPI_CPU1_CPU0_P0P1_DN<1>
J 0
(2735 1785);
DISPLAY 0.659574 (2735 1785);
PAINT MONO (2735 1785);
DISPLAY INVISIBLE (2735 1785);
FORCEPROP 1 LASTPIN (2725 1775) BN 1
J 0
(2713 1783);
DISPLAY 0.680851 (2713 1783);
PAINT GREEN (2713 1783);
FORCEPROP 2 LAST CDS_LIB standard
J 0
(2775 1775);
PAINT MONO (2775 1775);
DISPLAY INVISIBLE (2775 1775);
FORCEPROP 1 LAST BODY_TYPE PLUMBING
J 0
(2775 1825);
DISPLAY 0.872340 (2775 1825);
PAINT GREEN (2775 1825);
DISPLAY INVISIBLE (2775 1825);
FORCEPROP 1 LAST HDL_TAP TRUE
J 0
(3100 1650);
DISPLAY 0.872340 (3100 1650);
DISPLAY INVISIBLE (3100 1650);
FORCEPROP 1 LAST PATH I53
J 0
(2773 1775);
DISPLAY 0.872340 (2773 1775);
PAINT GREEN (2773 1775);
DISPLAY INVISIBLE (2773 1775);
FORCEADD TAP..1
(2775 1825);
FORCEPROP 3 LASTPIN (2725 1825) SIG_NAME UPI_CPU1_CPU0_P0P1_DN<2>
J 0
(2735 1835);
DISPLAY 0.659574 (2735 1835);
PAINT MONO (2735 1835);
DISPLAY INVISIBLE (2735 1835);
FORCEPROP 1 LASTPIN (2725 1825) BN 2
J 0
(2713 1833);
DISPLAY 0.680851 (2713 1833);
PAINT GREEN (2713 1833);
FORCEPROP 2 LAST CDS_LIB standard
J 0
(2775 1825);
PAINT MONO (2775 1825);
DISPLAY INVISIBLE (2775 1825);
FORCEPROP 1 LAST BODY_TYPE PLUMBING
J 0
(2775 1875);
DISPLAY 0.872340 (2775 1875);
PAINT GREEN (2775 1875);
DISPLAY INVISIBLE (2775 1875);
FORCEPROP 1 LAST HDL_TAP TRUE
J 0
(3100 1700);
DISPLAY 0.872340 (3100 1700);
DISPLAY INVISIBLE (3100 1700);
FORCEPROP 1 LAST PATH I54
J 0
(2773 1825);
DISPLAY 0.872340 (2773 1825);
PAINT GREEN (2773 1825);
DISPLAY INVISIBLE (2773 1825);
FORCEADD TAP..1
(2775 1975);
FORCEPROP 3 LASTPIN (2725 1975) SIG_NAME UPI_CPU1_CPU0_P0P1_DN<5>
J 0
(2735 1985);
DISPLAY 0.659574 (2735 1985);
PAINT MONO (2735 1985);
DISPLAY INVISIBLE (2735 1985);
FORCEPROP 1 LASTPIN (2725 1975) BN 5
J 0
(2713 1983);
DISPLAY 0.680851 (2713 1983);
PAINT GREEN (2713 1983);
FORCEPROP 2 LAST CDS_LIB standard
J 0
(2775 1975);
PAINT MONO (2775 1975);
DISPLAY INVISIBLE (2775 1975);
FORCEPROP 1 LAST BODY_TYPE PLUMBING
J 0
(2775 2025);
DISPLAY 0.872340 (2775 2025);
PAINT GREEN (2775 2025);
DISPLAY INVISIBLE (2775 2025);
FORCEPROP 1 LAST HDL_TAP TRUE
J 0
(3100 1850);
DISPLAY 0.872340 (3100 1850);
DISPLAY INVISIBLE (3100 1850);
FORCEPROP 1 LAST PATH I55
J 0
(2773 1975);
DISPLAY 0.872340 (2773 1975);
PAINT GREEN (2773 1975);
DISPLAY INVISIBLE (2773 1975);
FORCEADD TAP..1
(2775 1925);
FORCEPROP 3 LASTPIN (2725 1925) SIG_NAME UPI_CPU1_CPU0_P0P1_DN<4>
J 0
(2735 1935);
DISPLAY 0.659574 (2735 1935);
PAINT MONO (2735 1935);
DISPLAY INVISIBLE (2735 1935);
FORCEPROP 1 LASTPIN (2725 1925) BN 4
J 0
(2713 1933);
DISPLAY 0.680851 (2713 1933);
PAINT GREEN (2713 1933);
FORCEPROP 2 LAST CDS_LIB standard
J 0
(2775 1925);
PAINT MONO (2775 1925);
DISPLAY INVISIBLE (2775 1925);
FORCEPROP 1 LAST BODY_TYPE PLUMBING
J 0
(2775 1975);
DISPLAY 0.872340 (2775 1975);
PAINT GREEN (2775 1975);
DISPLAY INVISIBLE (2775 1975);
FORCEPROP 1 LAST HDL_TAP TRUE
J 0
(3100 1800);
DISPLAY 0.872340 (3100 1800);
DISPLAY INVISIBLE (3100 1800);
FORCEPROP 1 LAST PATH I56
J 0
(2773 1925);
DISPLAY 0.872340 (2773 1925);
PAINT GREEN (2773 1925);
DISPLAY INVISIBLE (2773 1925);
FORCEADD TAP..1
(2775 1875);
FORCEPROP 3 LASTPIN (2725 1875) SIG_NAME UPI_CPU1_CPU0_P0P1_DN<3>
J 0
(2735 1885);
DISPLAY 0.659574 (2735 1885);
PAINT MONO (2735 1885);
DISPLAY INVISIBLE (2735 1885);
FORCEPROP 1 LASTPIN (2725 1875) BN 3
J 0
(2713 1883);
DISPLAY 0.680851 (2713 1883);
PAINT GREEN (2713 1883);
FORCEPROP 2 LAST CDS_LIB standard
J 0
(2775 1875);
PAINT MONO (2775 1875);
DISPLAY INVISIBLE (2775 1875);
FORCEPROP 1 LAST BODY_TYPE PLUMBING
J 0
(2775 1925);
DISPLAY 0.872340 (2775 1925);
PAINT GREEN (2775 1925);
DISPLAY INVISIBLE (2775 1925);
FORCEPROP 1 LAST HDL_TAP TRUE
J 0
(3100 1750);
DISPLAY 0.872340 (3100 1750);
DISPLAY INVISIBLE (3100 1750);
FORCEPROP 1 LAST PATH I57
J 0
(2773 1875);
DISPLAY 0.872340 (2773 1875);
PAINT GREEN (2773 1875);
DISPLAY INVISIBLE (2773 1875);
FORCEADD TAP..1
(2775 2025);
FORCEPROP 3 LASTPIN (2725 2025) SIG_NAME UPI_CPU1_CPU0_P0P1_DN<6>
J 0
(2735 2035);
DISPLAY 0.659574 (2735 2035);
PAINT MONO (2735 2035);
DISPLAY INVISIBLE (2735 2035);
FORCEPROP 1 LASTPIN (2725 2025) BN 6
J 0
(2713 2033);
DISPLAY 0.680851 (2713 2033);
PAINT GREEN (2713 2033);
FORCEPROP 2 LAST CDS_LIB standard
J 0
(2775 2025);
PAINT MONO (2775 2025);
DISPLAY INVISIBLE (2775 2025);
FORCEPROP 1 LAST BODY_TYPE PLUMBING
J 0
(2775 2075);
DISPLAY 0.872340 (2775 2075);
PAINT GREEN (2775 2075);
DISPLAY INVISIBLE (2775 2075);
FORCEPROP 1 LAST HDL_TAP TRUE
J 0
(3100 1900);
DISPLAY 0.872340 (3100 1900);
DISPLAY INVISIBLE (3100 1900);
FORCEPROP 1 LAST PATH I58
J 0
(2773 2025);
DISPLAY 0.872340 (2773 2025);
PAINT GREEN (2773 2025);
DISPLAY INVISIBLE (2773 2025);
FORCEADD TAP..1
(2775 2075);
FORCEPROP 3 LASTPIN (2725 2075) SIG_NAME UPI_CPU1_CPU0_P0P1_DN<7>
J 0
(2735 2085);
DISPLAY 0.659574 (2735 2085);
PAINT MONO (2735 2085);
DISPLAY INVISIBLE (2735 2085);
FORCEPROP 1 LASTPIN (2725 2075) BN 7
J 0
(2713 2083);
DISPLAY 0.680851 (2713 2083);
PAINT GREEN (2713 2083);
FORCEPROP 2 LAST CDS_LIB standard
J 0
(2775 2075);
PAINT MONO (2775 2075);
DISPLAY INVISIBLE (2775 2075);
FORCEPROP 1 LAST BODY_TYPE PLUMBING
J 0
(2775 2125);
DISPLAY 0.872340 (2775 2125);
PAINT GREEN (2775 2125);
DISPLAY INVISIBLE (2775 2125);
FORCEPROP 1 LAST HDL_TAP TRUE
J 0
(3100 1950);
DISPLAY 0.872340 (3100 1950);
DISPLAY INVISIBLE (3100 1950);
FORCEPROP 1 LAST PATH I59
J 0
(2773 2075);
DISPLAY 0.872340 (2773 2075);
PAINT GREEN (2773 2075);
DISPLAY INVISIBLE (2773 2075);
FORCEADD TAP..1
R 2
(-600 1975);
FORCEPROP 3 LASTPIN (-550 1975) SIG_NAME UPI_CPU0_CPU1_P1P0_DN<5>
J 0
(-540 1985);
DISPLAY 0.659574 (-540 1985);
PAINT MONO (-540 1985);
DISPLAY INVISIBLE (-540 1985);
FORCEPROP 1 LASTPIN (-550 1975) BN 5
J 2
(-538 1983);
DISPLAY 0.680851 (-538 1983);
PAINT GREEN (-538 1983);
FORCEPROP 2 LAST CDS_LIB standard
J 0
(-600 1975);
DISPLAY INVISIBLE (-600 1975);
FORCEPROP 1 LAST BODY_TYPE PLUMBING
J 2
(-600 2025);
DISPLAY 0.872340 (-600 2025);
PAINT GREEN (-600 2025);
DISPLAY INVISIBLE (-600 2025);
FORCEPROP 1 LAST HDL_TAP TRUE
J 2
(-925 1850);
DISPLAY 0.872340 (-925 1850);
DISPLAY INVISIBLE (-925 1850);
FORCEPROP 1 LAST PATH I6
J 2
(-598 1975);
DISPLAY 0.872340 (-598 1975);
PAINT GREEN (-598 1975);
DISPLAY INVISIBLE (-598 1975);
FORCEADD TAP..1
(2775 2225);
FORCEPROP 3 LASTPIN (2725 2225) SIG_NAME UPI_CPU1_CPU0_P0P1_DN<10>
J 0
(2735 2235);
DISPLAY 0.659574 (2735 2235);
PAINT MONO (2735 2235);
DISPLAY INVISIBLE (2735 2235);
FORCEPROP 1 LASTPIN (2725 2225) BN 10
J 0
(2713 2233);
DISPLAY 0.680851 (2713 2233);
PAINT GREEN (2713 2233);
FORCEPROP 2 LAST CDS_LIB standard
J 0
(2775 2225);
PAINT MONO (2775 2225);
DISPLAY INVISIBLE (2775 2225);
FORCEPROP 1 LAST BODY_TYPE PLUMBING
J 0
(2775 2275);
DISPLAY 0.872340 (2775 2275);
PAINT GREEN (2775 2275);
DISPLAY INVISIBLE (2775 2275);
FORCEPROP 1 LAST HDL_TAP TRUE
J 0
(3100 2100);
DISPLAY 0.872340 (3100 2100);
DISPLAY INVISIBLE (3100 2100);
FORCEPROP 1 LAST PATH I60
J 0
(2773 2225);
DISPLAY 0.872340 (2773 2225);
PAINT GREEN (2773 2225);
DISPLAY INVISIBLE (2773 2225);
FORCEADD TAP..1
(2775 2125);
FORCEPROP 3 LASTPIN (2725 2125) SIG_NAME UPI_CPU1_CPU0_P0P1_DN<8>
J 0
(2735 2135);
DISPLAY 0.659574 (2735 2135);
PAINT MONO (2735 2135);
DISPLAY INVISIBLE (2735 2135);
FORCEPROP 1 LASTPIN (2725 2125) BN 8
J 0
(2713 2133);
DISPLAY 0.680851 (2713 2133);
PAINT GREEN (2713 2133);
FORCEPROP 2 LAST CDS_LIB standard
J 0
(2775 2125);
PAINT MONO (2775 2125);
DISPLAY INVISIBLE (2775 2125);
FORCEPROP 1 LAST BODY_TYPE PLUMBING
J 0
(2775 2175);
DISPLAY 0.872340 (2775 2175);
PAINT GREEN (2775 2175);
DISPLAY INVISIBLE (2775 2175);
FORCEPROP 1 LAST HDL_TAP TRUE
J 0
(3100 2000);
DISPLAY 0.872340 (3100 2000);
DISPLAY INVISIBLE (3100 2000);
FORCEPROP 1 LAST PATH I61
J 0
(2773 2125);
DISPLAY 0.872340 (2773 2125);
PAINT GREEN (2773 2125);
DISPLAY INVISIBLE (2773 2125);
FORCEADD TAP..1
(2775 2175);
FORCEPROP 3 LASTPIN (2725 2175) SIG_NAME UPI_CPU1_CPU0_P0P1_DN<9>
J 0
(2735 2185);
DISPLAY 0.659574 (2735 2185);
PAINT MONO (2735 2185);
DISPLAY INVISIBLE (2735 2185);
FORCEPROP 1 LASTPIN (2725 2175) BN 9
J 0
(2713 2183);
DISPLAY 0.680851 (2713 2183);
PAINT GREEN (2713 2183);
FORCEPROP 2 LAST CDS_LIB standard
J 0
(2775 2175);
PAINT MONO (2775 2175);
DISPLAY INVISIBLE (2775 2175);
FORCEPROP 1 LAST BODY_TYPE PLUMBING
J 0
(2775 2225);
DISPLAY 0.872340 (2775 2225);
PAINT GREEN (2775 2225);
DISPLAY INVISIBLE (2775 2225);
FORCEPROP 1 LAST HDL_TAP TRUE
J 0
(3100 2050);
DISPLAY 0.872340 (3100 2050);
DISPLAY INVISIBLE (3100 2050);
FORCEPROP 1 LAST PATH I62
J 0
(2773 2175);
DISPLAY 0.872340 (2773 2175);
PAINT GREEN (2773 2175);
DISPLAY INVISIBLE (2773 2175);
FORCEADD TAP..1
(2775 2325);
FORCEPROP 3 LASTPIN (2725 2325) SIG_NAME UPI_CPU1_CPU0_P0P1_DN<12>
J 0
(2735 2335);
DISPLAY 0.659574 (2735 2335);
PAINT MONO (2735 2335);
DISPLAY INVISIBLE (2735 2335);
FORCEPROP 1 LASTPIN (2725 2325) BN 12
J 0
(2713 2333);
DISPLAY 0.680851 (2713 2333);
PAINT GREEN (2713 2333);
FORCEPROP 2 LAST CDS_LIB standard
J 0
(2775 2325);
PAINT MONO (2775 2325);
DISPLAY INVISIBLE (2775 2325);
FORCEPROP 1 LAST BODY_TYPE PLUMBING
J 0
(2775 2375);
DISPLAY 0.872340 (2775 2375);
PAINT GREEN (2775 2375);
DISPLAY INVISIBLE (2775 2375);
FORCEPROP 1 LAST HDL_TAP TRUE
J 0
(3100 2200);
DISPLAY 0.872340 (3100 2200);
DISPLAY INVISIBLE (3100 2200);
FORCEPROP 1 LAST PATH I63
J 0
(2773 2325);
DISPLAY 0.872340 (2773 2325);
PAINT GREEN (2773 2325);
DISPLAY INVISIBLE (2773 2325);
FORCEADD TAP..1
(2775 2275);
FORCEPROP 3 LASTPIN (2725 2275) SIG_NAME UPI_CPU1_CPU0_P0P1_DN<11>
J 0
(2735 2285);
DISPLAY 0.659574 (2735 2285);
PAINT MONO (2735 2285);
DISPLAY INVISIBLE (2735 2285);
FORCEPROP 1 LASTPIN (2725 2275) BN 11
J 0
(2713 2283);
DISPLAY 0.680851 (2713 2283);
PAINT GREEN (2713 2283);
FORCEPROP 2 LAST CDS_LIB standard
J 0
(2775 2275);
PAINT MONO (2775 2275);
DISPLAY INVISIBLE (2775 2275);
FORCEPROP 1 LAST BODY_TYPE PLUMBING
J 0
(2775 2325);
DISPLAY 0.872340 (2775 2325);
PAINT GREEN (2775 2325);
DISPLAY INVISIBLE (2775 2325);
FORCEPROP 1 LAST HDL_TAP TRUE
J 0
(3100 2150);
DISPLAY 0.872340 (3100 2150);
DISPLAY INVISIBLE (3100 2150);
FORCEPROP 1 LAST PATH I64
J 0
(2773 2275);
DISPLAY 0.872340 (2773 2275);
PAINT GREEN (2773 2275);
DISPLAY INVISIBLE (2773 2275);
FORCEADD TAP..1
(2775 2475);
FORCEPROP 3 LASTPIN (2725 2475) SIG_NAME UPI_CPU1_CPU0_P0P1_DN<15>
J 0
(2735 2485);
DISPLAY 0.659574 (2735 2485);
PAINT MONO (2735 2485);
DISPLAY INVISIBLE (2735 2485);
FORCEPROP 1 LASTPIN (2725 2475) BN 15
J 0
(2713 2483);
DISPLAY 0.680851 (2713 2483);
PAINT GREEN (2713 2483);
FORCEPROP 2 LAST CDS_LIB standard
J 0
(2775 2475);
PAINT MONO (2775 2475);
DISPLAY INVISIBLE (2775 2475);
FORCEPROP 1 LAST BODY_TYPE PLUMBING
J 0
(2775 2525);
DISPLAY 0.872340 (2775 2525);
PAINT GREEN (2775 2525);
DISPLAY INVISIBLE (2775 2525);
FORCEPROP 1 LAST HDL_TAP TRUE
J 0
(3100 2350);
DISPLAY 0.872340 (3100 2350);
DISPLAY INVISIBLE (3100 2350);
FORCEPROP 1 LAST PATH I65
J 0
(2773 2475);
DISPLAY 0.872340 (2773 2475);
PAINT GREEN (2773 2475);
DISPLAY INVISIBLE (2773 2475);
FORCEADD TAP..1
(2775 2375);
FORCEPROP 3 LASTPIN (2725 2375) SIG_NAME UPI_CPU1_CPU0_P0P1_DN<13>
J 0
(2735 2385);
DISPLAY 0.659574 (2735 2385);
PAINT MONO (2735 2385);
DISPLAY INVISIBLE (2735 2385);
FORCEPROP 1 LASTPIN (2725 2375) BN 13
J 0
(2713 2383);
DISPLAY 0.680851 (2713 2383);
PAINT GREEN (2713 2383);
FORCEPROP 2 LAST CDS_LIB standard
J 0
(2775 2375);
PAINT MONO (2775 2375);
DISPLAY INVISIBLE (2775 2375);
FORCEPROP 1 LAST BODY_TYPE PLUMBING
J 0
(2775 2425);
DISPLAY 0.872340 (2775 2425);
PAINT GREEN (2775 2425);
DISPLAY INVISIBLE (2775 2425);
FORCEPROP 1 LAST HDL_TAP TRUE
J 0
(3100 2250);
DISPLAY 0.872340 (3100 2250);
DISPLAY INVISIBLE (3100 2250);
FORCEPROP 1 LAST PATH I66
J 0
(2773 2375);
DISPLAY 0.872340 (2773 2375);
PAINT GREEN (2773 2375);
DISPLAY INVISIBLE (2773 2375);
FORCEADD TAP..1
(2775 2425);
FORCEPROP 3 LASTPIN (2725 2425) SIG_NAME UPI_CPU1_CPU0_P0P1_DN<14>
J 0
(2735 2435);
DISPLAY 0.659574 (2735 2435);
PAINT MONO (2735 2435);
DISPLAY INVISIBLE (2735 2435);
FORCEPROP 1 LASTPIN (2725 2425) BN 14
J 0
(2713 2433);
DISPLAY 0.680851 (2713 2433);
PAINT GREEN (2713 2433);
FORCEPROP 2 LAST CDS_LIB standard
J 0
(2775 2425);
PAINT MONO (2775 2425);
DISPLAY INVISIBLE (2775 2425);
FORCEPROP 1 LAST BODY_TYPE PLUMBING
J 0
(2775 2475);
DISPLAY 0.872340 (2775 2475);
PAINT GREEN (2775 2475);
DISPLAY INVISIBLE (2775 2475);
FORCEPROP 1 LAST HDL_TAP TRUE
J 0
(3100 2300);
DISPLAY 0.872340 (3100 2300);
DISPLAY INVISIBLE (3100 2300);
FORCEPROP 1 LAST PATH I67
J 0
(2773 2425);
DISPLAY 0.872340 (2773 2425);
PAINT GREEN (2773 2425);
DISPLAY INVISIBLE (2773 2425);
FORCEADD TAP..1
(2775 2575);
FORCEPROP 3 LASTPIN (2725 2575) SIG_NAME UPI_CPU1_CPU0_P0P1_DN<17>
J 0
(2735 2585);
DISPLAY 0.659574 (2735 2585);
PAINT MONO (2735 2585);
DISPLAY INVISIBLE (2735 2585);
FORCEPROP 1 LASTPIN (2725 2575) BN 17
J 0
(2713 2583);
DISPLAY 0.680851 (2713 2583);
PAINT GREEN (2713 2583);
FORCEPROP 2 LAST CDS_LIB standard
J 0
(2775 2575);
DISPLAY INVISIBLE (2775 2575);
FORCEPROP 1 LAST BODY_TYPE PLUMBING
J 0
(2775 2625);
DISPLAY 0.872340 (2775 2625);
PAINT GREEN (2775 2625);
DISPLAY INVISIBLE (2775 2625);
FORCEPROP 1 LAST HDL_TAP TRUE
J 0
(3100 2450);
DISPLAY 0.872340 (3100 2450);
DISPLAY INVISIBLE (3100 2450);
FORCEPROP 1 LAST PATH I68
J 0
(2773 2575);
DISPLAY 0.872340 (2773 2575);
PAINT GREEN (2773 2575);
DISPLAY INVISIBLE (2773 2575);
FORCEADD TAP..1
(2775 2525);
FORCEPROP 3 LASTPIN (2725 2525) SIG_NAME UPI_CPU1_CPU0_P0P1_DN<16>
J 0
(2735 2535);
DISPLAY 0.659574 (2735 2535);
PAINT MONO (2735 2535);
DISPLAY INVISIBLE (2735 2535);
FORCEPROP 1 LASTPIN (2725 2525) BN 16
J 0
(2713 2533);
DISPLAY 0.680851 (2713 2533);
PAINT GREEN (2713 2533);
FORCEPROP 2 LAST CDS_LIB standard
J 0
(2775 2525);
PAINT MONO (2775 2525);
DISPLAY INVISIBLE (2775 2525);
FORCEPROP 1 LAST BODY_TYPE PLUMBING
J 0
(2775 2575);
DISPLAY 0.872340 (2775 2575);
PAINT GREEN (2775 2575);
DISPLAY INVISIBLE (2775 2575);
FORCEPROP 1 LAST HDL_TAP TRUE
J 0
(3100 2400);
DISPLAY 0.872340 (3100 2400);
DISPLAY INVISIBLE (3100 2400);
FORCEPROP 1 LAST PATH I69
J 0
(2773 2525);
DISPLAY 0.872340 (2773 2525);
PAINT GREEN (2773 2525);
DISPLAY INVISIBLE (2773 2525);
FORCEADD TAP..1
R 2
(-600 2075);
FORCEPROP 3 LASTPIN (-550 2075) SIG_NAME UPI_CPU0_CPU1_P1P0_DN<7>
J 0
(-540 2085);
DISPLAY 0.659574 (-540 2085);
PAINT MONO (-540 2085);
DISPLAY INVISIBLE (-540 2085);
FORCEPROP 1 LASTPIN (-550 2075) BN 7
J 2
(-538 2083);
DISPLAY 0.680851 (-538 2083);
PAINT GREEN (-538 2083);
FORCEPROP 2 LAST CDS_LIB standard
J 0
(-600 2075);
DISPLAY INVISIBLE (-600 2075);
FORCEPROP 1 LAST BODY_TYPE PLUMBING
J 2
(-600 2125);
DISPLAY 0.872340 (-600 2125);
PAINT GREEN (-600 2125);
DISPLAY INVISIBLE (-600 2125);
FORCEPROP 1 LAST HDL_TAP TRUE
J 2
(-925 1950);
DISPLAY 0.872340 (-925 1950);
DISPLAY INVISIBLE (-925 1950);
FORCEPROP 1 LAST PATH I7
J 2
(-598 2075);
DISPLAY 0.872340 (-598 2075);
PAINT GREEN (-598 2075);
DISPLAY INVISIBLE (-598 2075);
FORCEADD TAP..1
(2775 2625);
FORCEPROP 3 LASTPIN (2725 2625) SIG_NAME UPI_CPU1_CPU0_P0P1_DN<18>
J 0
(2735 2635);
DISPLAY 0.659574 (2735 2635);
PAINT MONO (2735 2635);
DISPLAY INVISIBLE (2735 2635);
FORCEPROP 1 LASTPIN (2725 2625) BN 18
J 0
(2713 2633);
DISPLAY 0.680851 (2713 2633);
PAINT GREEN (2713 2633);
FORCEPROP 2 LAST CDS_LIB standard
J 0
(2775 2625);
DISPLAY INVISIBLE (2775 2625);
FORCEPROP 1 LAST BODY_TYPE PLUMBING
J 0
(2775 2675);
DISPLAY 0.872340 (2775 2675);
PAINT GREEN (2775 2675);
DISPLAY INVISIBLE (2775 2675);
FORCEPROP 1 LAST HDL_TAP TRUE
J 0
(3100 2500);
DISPLAY 0.872340 (3100 2500);
DISPLAY INVISIBLE (3100 2500);
FORCEPROP 1 LAST PATH I70
J 0
(2773 2625);
DISPLAY 0.872340 (2773 2625);
PAINT GREEN (2773 2625);
DISPLAY INVISIBLE (2773 2625);
FORCEADD TAP..1
(2775 2675);
FORCEPROP 3 LASTPIN (2725 2675) SIG_NAME UPI_CPU1_CPU0_P0P1_DN<19>
J 0
(2735 2685);
DISPLAY 0.659574 (2735 2685);
PAINT MONO (2735 2685);
DISPLAY INVISIBLE (2735 2685);
FORCEPROP 1 LASTPIN (2725 2675) BN 19
J 0
(2713 2683);
DISPLAY 0.680851 (2713 2683);
PAINT GREEN (2713 2683);
FORCEPROP 2 LAST CDS_LIB standard
J 0
(2775 2675);
DISPLAY INVISIBLE (2775 2675);
FORCEPROP 1 LAST BODY_TYPE PLUMBING
J 0
(2775 2725);
DISPLAY 0.872340 (2775 2725);
PAINT GREEN (2775 2725);
DISPLAY INVISIBLE (2775 2725);
FORCEPROP 1 LAST HDL_TAP TRUE
J 0
(3100 2550);
DISPLAY 0.872340 (3100 2550);
DISPLAY INVISIBLE (3100 2550);
FORCEPROP 1 LAST PATH I71
J 0
(2773 2675);
DISPLAY 0.872340 (2773 2675);
PAINT GREEN (2773 2675);
DISPLAY INVISIBLE (2773 2675);
FORCEADD TAP..1
(2775 2725);
FORCEPROP 3 LASTPIN (2725 2725) SIG_NAME UPI_CPU1_CPU0_P0P1_DN<20>
J 0
(2735 2735);
DISPLAY 0.659574 (2735 2735);
PAINT MONO (2735 2735);
DISPLAY INVISIBLE (2735 2735);
FORCEPROP 1 LASTPIN (2725 2725) BN 20
J 0
(2713 2733);
DISPLAY 0.680851 (2713 2733);
PAINT GREEN (2713 2733);
FORCEPROP 2 LAST CDS_LIB standard
J 0
(2775 2725);
DISPLAY INVISIBLE (2775 2725);
FORCEPROP 1 LAST BODY_TYPE PLUMBING
J 0
(2775 2775);
DISPLAY 0.872340 (2775 2775);
PAINT GREEN (2775 2775);
DISPLAY INVISIBLE (2775 2775);
FORCEPROP 1 LAST HDL_TAP TRUE
J 0
(3100 2600);
DISPLAY 0.872340 (3100 2600);
DISPLAY INVISIBLE (3100 2600);
FORCEPROP 1 LAST PATH I72
J 0
(2773 2725);
DISPLAY 0.872340 (2773 2725);
PAINT GREEN (2773 2725);
DISPLAY INVISIBLE (2773 2725);
FORCEADD TAP..1
(2775 2875);
FORCEPROP 3 LASTPIN (2725 2875) SIG_NAME UPI_CPU1_CPU0_P0P1_DN<23>
J 0
(2735 2885);
DISPLAY 0.659574 (2735 2885);
PAINT MONO (2735 2885);
DISPLAY INVISIBLE (2735 2885);
FORCEPROP 1 LASTPIN (2725 2875) BN 23
J 0
(2713 2883);
DISPLAY 0.680851 (2713 2883);
PAINT GREEN (2713 2883);
FORCEPROP 2 LAST CDS_LIB standard
J 0
(2775 2875);
DISPLAY INVISIBLE (2775 2875);
FORCEPROP 1 LAST BODY_TYPE PLUMBING
J 0
(2775 2925);
DISPLAY 0.872340 (2775 2925);
PAINT GREEN (2775 2925);
DISPLAY INVISIBLE (2775 2925);
FORCEPROP 1 LAST HDL_TAP TRUE
J 0
(3100 2750);
DISPLAY 0.872340 (3100 2750);
DISPLAY INVISIBLE (3100 2750);
FORCEPROP 1 LAST PATH I73
J 0
(2773 2875);
DISPLAY 0.872340 (2773 2875);
PAINT GREEN (2773 2875);
DISPLAY INVISIBLE (2773 2875);
FORCEADD TAP..1
(2775 2775);
FORCEPROP 3 LASTPIN (2725 2775) SIG_NAME UPI_CPU1_CPU0_P0P1_DN<21>
J 0
(2735 2785);
DISPLAY 0.659574 (2735 2785);
PAINT MONO (2735 2785);
DISPLAY INVISIBLE (2735 2785);
FORCEPROP 1 LASTPIN (2725 2775) BN 21
J 0
(2713 2783);
DISPLAY 0.680851 (2713 2783);
PAINT GREEN (2713 2783);
FORCEPROP 2 LAST CDS_LIB standard
J 0
(2775 2775);
DISPLAY INVISIBLE (2775 2775);
FORCEPROP 1 LAST BODY_TYPE PLUMBING
J 0
(2775 2825);
DISPLAY 0.872340 (2775 2825);
PAINT GREEN (2775 2825);
DISPLAY INVISIBLE (2775 2825);
FORCEPROP 1 LAST HDL_TAP TRUE
J 0
(3100 2650);
DISPLAY 0.872340 (3100 2650);
DISPLAY INVISIBLE (3100 2650);
FORCEPROP 1 LAST PATH I74
J 0
(2773 2775);
DISPLAY 0.872340 (2773 2775);
PAINT GREEN (2773 2775);
DISPLAY INVISIBLE (2773 2775);
FORCEADD TAP..1
(2775 2975);
FORCEPROP 3 LASTPIN (2725 2975) SIG_NAME UPI_CPU1_CPU0_P0P1_DP<0>
J 0
(2735 2985);
DISPLAY 0.659574 (2735 2985);
PAINT MONO (2735 2985);
DISPLAY INVISIBLE (2735 2985);
FORCEPROP 1 LASTPIN (2725 2975) BN 0
J 0
(2713 2983);
DISPLAY 0.680851 (2713 2983);
PAINT GREEN (2713 2983);
FORCEPROP 2 LAST CDS_LIB standard
J 0
(2775 2975);
PAINT MONO (2775 2975);
DISPLAY INVISIBLE (2775 2975);
FORCEPROP 1 LAST BODY_TYPE PLUMBING
J 0
(2775 3025);
DISPLAY 0.872340 (2775 3025);
PAINT GREEN (2775 3025);
DISPLAY INVISIBLE (2775 3025);
FORCEPROP 1 LAST HDL_TAP TRUE
J 0
(3100 2850);
DISPLAY 0.872340 (3100 2850);
DISPLAY INVISIBLE (3100 2850);
FORCEPROP 1 LAST PATH I75
J 0
(2773 2975);
DISPLAY 0.872340 (2773 2975);
PAINT GREEN (2773 2975);
DISPLAY INVISIBLE (2773 2975);
FORCEADD TAP..1
(2775 2825);
FORCEPROP 3 LASTPIN (2725 2825) SIG_NAME UPI_CPU1_CPU0_P0P1_DN<22>
J 0
(2735 2835);
DISPLAY 0.659574 (2735 2835);
PAINT MONO (2735 2835);
DISPLAY INVISIBLE (2735 2835);
FORCEPROP 1 LASTPIN (2725 2825) BN 22
J 0
(2713 2833);
DISPLAY 0.680851 (2713 2833);
PAINT GREEN (2713 2833);
FORCEPROP 2 LAST CDS_LIB standard
J 0
(2775 2825);
DISPLAY INVISIBLE (2775 2825);
FORCEPROP 1 LAST BODY_TYPE PLUMBING
J 0
(2775 2875);
DISPLAY 0.872340 (2775 2875);
PAINT GREEN (2775 2875);
DISPLAY INVISIBLE (2775 2875);
FORCEPROP 1 LAST HDL_TAP TRUE
J 0
(3100 2700);
DISPLAY 0.872340 (3100 2700);
DISPLAY INVISIBLE (3100 2700);
FORCEPROP 1 LAST PATH I76
J 0
(2773 2825);
DISPLAY 0.872340 (2773 2825);
PAINT GREEN (2773 2825);
DISPLAY INVISIBLE (2773 2825);
FORCEADD TAP..1
(2775 3075);
FORCEPROP 3 LASTPIN (2725 3075) SIG_NAME UPI_CPU1_CPU0_P0P1_DP<2>
J 0
(2735 3085);
DISPLAY 0.659574 (2735 3085);
PAINT MONO (2735 3085);
DISPLAY INVISIBLE (2735 3085);
FORCEPROP 1 LASTPIN (2725 3075) BN 2
J 0
(2713 3083);
DISPLAY 0.680851 (2713 3083);
PAINT GREEN (2713 3083);
FORCEPROP 2 LAST CDS_LIB standard
J 0
(2775 3075);
PAINT MONO (2775 3075);
DISPLAY INVISIBLE (2775 3075);
FORCEPROP 1 LAST BODY_TYPE PLUMBING
J 0
(2775 3125);
DISPLAY 0.872340 (2775 3125);
PAINT GREEN (2775 3125);
DISPLAY INVISIBLE (2775 3125);
FORCEPROP 1 LAST HDL_TAP TRUE
J 0
(3100 2950);
DISPLAY 0.872340 (3100 2950);
DISPLAY INVISIBLE (3100 2950);
FORCEPROP 1 LAST PATH I77
J 0
(2773 3075);
DISPLAY 0.872340 (2773 3075);
PAINT GREEN (2773 3075);
DISPLAY INVISIBLE (2773 3075);
FORCEADD TAP..1
(2775 3025);
FORCEPROP 3 LASTPIN (2725 3025) SIG_NAME UPI_CPU1_CPU0_P0P1_DP<1>
J 0
(2735 3035);
DISPLAY 0.659574 (2735 3035);
PAINT MONO (2735 3035);
DISPLAY INVISIBLE (2735 3035);
FORCEPROP 1 LASTPIN (2725 3025) BN 1
J 0
(2713 3033);
DISPLAY 0.680851 (2713 3033);
PAINT GREEN (2713 3033);
FORCEPROP 2 LAST CDS_LIB standard
J 0
(2775 3025);
PAINT MONO (2775 3025);
DISPLAY INVISIBLE (2775 3025);
FORCEPROP 1 LAST BODY_TYPE PLUMBING
J 0
(2775 3075);
DISPLAY 0.872340 (2775 3075);
PAINT GREEN (2775 3075);
DISPLAY INVISIBLE (2775 3075);
FORCEPROP 1 LAST HDL_TAP TRUE
J 0
(3100 2900);
DISPLAY 0.872340 (3100 2900);
DISPLAY INVISIBLE (3100 2900);
FORCEPROP 1 LAST PATH I78
J 0
(2773 3025);
DISPLAY 0.872340 (2773 3025);
PAINT GREEN (2773 3025);
DISPLAY INVISIBLE (2773 3025);
FORCEADD TAP..1
(2775 3225);
FORCEPROP 3 LASTPIN (2725 3225) SIG_NAME UPI_CPU1_CPU0_P0P1_DP<5>
J 0
(2735 3235);
DISPLAY 0.659574 (2735 3235);
PAINT MONO (2735 3235);
DISPLAY INVISIBLE (2735 3235);
FORCEPROP 1 LASTPIN (2725 3225) BN 5
J 0
(2713 3233);
DISPLAY 0.680851 (2713 3233);
PAINT GREEN (2713 3233);
FORCEPROP 2 LAST CDS_LIB standard
J 0
(2775 3225);
PAINT MONO (2775 3225);
DISPLAY INVISIBLE (2775 3225);
FORCEPROP 1 LAST BODY_TYPE PLUMBING
J 0
(2775 3275);
DISPLAY 0.872340 (2775 3275);
PAINT GREEN (2775 3275);
DISPLAY INVISIBLE (2775 3275);
FORCEPROP 1 LAST HDL_TAP TRUE
J 0
(3100 3100);
DISPLAY 0.872340 (3100 3100);
DISPLAY INVISIBLE (3100 3100);
FORCEPROP 1 LAST PATH I79
J 0
(2773 3225);
DISPLAY 0.872340 (2773 3225);
PAINT GREEN (2773 3225);
DISPLAY INVISIBLE (2773 3225);
FORCEADD TAP..1
R 2
(-600 2025);
FORCEPROP 3 LASTPIN (-550 2025) SIG_NAME UPI_CPU0_CPU1_P1P0_DN<6>
J 0
(-540 2035);
DISPLAY 0.659574 (-540 2035);
PAINT MONO (-540 2035);
DISPLAY INVISIBLE (-540 2035);
FORCEPROP 1 LASTPIN (-550 2025) BN 6
J 2
(-538 2033);
DISPLAY 0.680851 (-538 2033);
PAINT GREEN (-538 2033);
FORCEPROP 2 LAST CDS_LIB standard
J 0
(-600 2025);
DISPLAY INVISIBLE (-600 2025);
FORCEPROP 1 LAST BODY_TYPE PLUMBING
J 2
(-600 2075);
DISPLAY 0.872340 (-600 2075);
PAINT GREEN (-600 2075);
DISPLAY INVISIBLE (-600 2075);
FORCEPROP 1 LAST HDL_TAP TRUE
J 2
(-925 1900);
DISPLAY 0.872340 (-925 1900);
DISPLAY INVISIBLE (-925 1900);
FORCEPROP 1 LAST PATH I8
J 2
(-598 2025);
DISPLAY 0.872340 (-598 2025);
PAINT GREEN (-598 2025);
DISPLAY INVISIBLE (-598 2025);
FORCEADD TAP..1
(2775 3125);
FORCEPROP 3 LASTPIN (2725 3125) SIG_NAME UPI_CPU1_CPU0_P0P1_DP<3>
J 0
(2735 3135);
DISPLAY 0.659574 (2735 3135);
PAINT MONO (2735 3135);
DISPLAY INVISIBLE (2735 3135);
FORCEPROP 1 LASTPIN (2725 3125) BN 3
J 0
(2713 3133);
DISPLAY 0.680851 (2713 3133);
PAINT GREEN (2713 3133);
FORCEPROP 2 LAST CDS_LIB standard
J 0
(2775 3125);
PAINT MONO (2775 3125);
DISPLAY INVISIBLE (2775 3125);
FORCEPROP 1 LAST BODY_TYPE PLUMBING
J 0
(2775 3175);
DISPLAY 0.872340 (2775 3175);
PAINT GREEN (2775 3175);
DISPLAY INVISIBLE (2775 3175);
FORCEPROP 1 LAST HDL_TAP TRUE
J 0
(3100 3000);
DISPLAY 0.872340 (3100 3000);
DISPLAY INVISIBLE (3100 3000);
FORCEPROP 1 LAST PATH I80
J 0
(2773 3125);
DISPLAY 0.872340 (2773 3125);
PAINT GREEN (2773 3125);
DISPLAY INVISIBLE (2773 3125);
FORCEADD TAP..1
(2775 3175);
FORCEPROP 3 LASTPIN (2725 3175) SIG_NAME UPI_CPU1_CPU0_P0P1_DP<4>
J 0
(2735 3185);
DISPLAY 0.659574 (2735 3185);
PAINT MONO (2735 3185);
DISPLAY INVISIBLE (2735 3185);
FORCEPROP 1 LASTPIN (2725 3175) BN 4
J 0
(2713 3183);
DISPLAY 0.680851 (2713 3183);
PAINT GREEN (2713 3183);
FORCEPROP 2 LAST CDS_LIB standard
J 0
(2775 3175);
PAINT MONO (2775 3175);
DISPLAY INVISIBLE (2775 3175);
FORCEPROP 1 LAST BODY_TYPE PLUMBING
J 0
(2775 3225);
DISPLAY 0.872340 (2775 3225);
PAINT GREEN (2775 3225);
DISPLAY INVISIBLE (2775 3225);
FORCEPROP 1 LAST HDL_TAP TRUE
J 0
(3100 3050);
DISPLAY 0.872340 (3100 3050);
DISPLAY INVISIBLE (3100 3050);
FORCEPROP 1 LAST PATH I81
J 0
(2773 3175);
DISPLAY 0.872340 (2773 3175);
PAINT GREEN (2773 3175);
DISPLAY INVISIBLE (2773 3175);
FORCEADD TAP..1
(2775 3425);
FORCEPROP 3 LASTPIN (2725 3425) SIG_NAME UPI_CPU1_CPU0_P0P1_DP<9>
J 0
(2735 3435);
DISPLAY 0.659574 (2735 3435);
PAINT MONO (2735 3435);
DISPLAY INVISIBLE (2735 3435);
FORCEPROP 1 LASTPIN (2725 3425) BN 9
J 0
(2713 3433);
DISPLAY 0.680851 (2713 3433);
PAINT GREEN (2713 3433);
FORCEPROP 2 LAST CDS_LIB standard
J 0
(2775 3425);
PAINT MONO (2775 3425);
DISPLAY INVISIBLE (2775 3425);
FORCEPROP 1 LAST BODY_TYPE PLUMBING
J 0
(2775 3475);
DISPLAY 0.872340 (2775 3475);
PAINT GREEN (2775 3475);
DISPLAY INVISIBLE (2775 3475);
FORCEPROP 1 LAST HDL_TAP TRUE
J 0
(3100 3300);
DISPLAY 0.872340 (3100 3300);
DISPLAY INVISIBLE (3100 3300);
FORCEPROP 1 LAST PATH I82
J 0
(2773 3425);
DISPLAY 0.872340 (2773 3425);
PAINT GREEN (2773 3425);
DISPLAY INVISIBLE (2773 3425);
FORCEADD TAP..1
(2775 3475);
FORCEPROP 3 LASTPIN (2725 3475) SIG_NAME UPI_CPU1_CPU0_P0P1_DP<10>
J 0
(2735 3485);
DISPLAY 0.659574 (2735 3485);
PAINT MONO (2735 3485);
DISPLAY INVISIBLE (2735 3485);
FORCEPROP 1 LASTPIN (2725 3475) BN 10
J 0
(2713 3483);
DISPLAY 0.680851 (2713 3483);
PAINT GREEN (2713 3483);
FORCEPROP 2 LAST CDS_LIB standard
J 0
(2775 3475);
PAINT MONO (2775 3475);
DISPLAY INVISIBLE (2775 3475);
FORCEPROP 1 LAST BODY_TYPE PLUMBING
J 0
(2775 3525);
DISPLAY 0.872340 (2775 3525);
PAINT GREEN (2775 3525);
DISPLAY INVISIBLE (2775 3525);
FORCEPROP 1 LAST HDL_TAP TRUE
J 0
(3100 3350);
DISPLAY 0.872340 (3100 3350);
DISPLAY INVISIBLE (3100 3350);
FORCEPROP 1 LAST PATH I83
J 0
(2773 3475);
DISPLAY 0.872340 (2773 3475);
PAINT GREEN (2773 3475);
DISPLAY INVISIBLE (2773 3475);
FORCEADD TAP..1
(2775 3375);
FORCEPROP 3 LASTPIN (2725 3375) SIG_NAME UPI_CPU1_CPU0_P0P1_DP<8>
J 0
(2735 3385);
DISPLAY 0.659574 (2735 3385);
PAINT MONO (2735 3385);
DISPLAY INVISIBLE (2735 3385);
FORCEPROP 1 LASTPIN (2725 3375) BN 8
J 0
(2713 3383);
DISPLAY 0.680851 (2713 3383);
PAINT GREEN (2713 3383);
FORCEPROP 2 LAST CDS_LIB standard
J 0
(2775 3375);
PAINT MONO (2775 3375);
DISPLAY INVISIBLE (2775 3375);
FORCEPROP 1 LAST BODY_TYPE PLUMBING
J 0
(2775 3425);
DISPLAY 0.872340 (2775 3425);
PAINT GREEN (2775 3425);
DISPLAY INVISIBLE (2775 3425);
FORCEPROP 1 LAST HDL_TAP TRUE
J 0
(3100 3250);
DISPLAY 0.872340 (3100 3250);
DISPLAY INVISIBLE (3100 3250);
FORCEPROP 1 LAST PATH I84
J 0
(2773 3375);
DISPLAY 0.872340 (2773 3375);
PAINT GREEN (2773 3375);
DISPLAY INVISIBLE (2773 3375);
FORCEADD TAP..1
(2775 3325);
FORCEPROP 3 LASTPIN (2725 3325) SIG_NAME UPI_CPU1_CPU0_P0P1_DP<7>
J 0
(2735 3335);
DISPLAY 0.659574 (2735 3335);
PAINT MONO (2735 3335);
DISPLAY INVISIBLE (2735 3335);
FORCEPROP 1 LASTPIN (2725 3325) BN 7
J 0
(2713 3333);
DISPLAY 0.680851 (2713 3333);
PAINT GREEN (2713 3333);
FORCEPROP 2 LAST CDS_LIB standard
J 0
(2775 3325);
PAINT MONO (2775 3325);
DISPLAY INVISIBLE (2775 3325);
FORCEPROP 1 LAST BODY_TYPE PLUMBING
J 0
(2775 3375);
DISPLAY 0.872340 (2775 3375);
PAINT GREEN (2775 3375);
DISPLAY INVISIBLE (2775 3375);
FORCEPROP 1 LAST HDL_TAP TRUE
J 0
(3100 3200);
DISPLAY 0.872340 (3100 3200);
DISPLAY INVISIBLE (3100 3200);
FORCEPROP 1 LAST PATH I85
J 0
(2773 3325);
DISPLAY 0.872340 (2773 3325);
PAINT GREEN (2773 3325);
DISPLAY INVISIBLE (2773 3325);
FORCEADD TAP..1
(2775 3275);
FORCEPROP 3 LASTPIN (2725 3275) SIG_NAME UPI_CPU1_CPU0_P0P1_DP<6>
J 0
(2735 3285);
DISPLAY 0.659574 (2735 3285);
PAINT MONO (2735 3285);
DISPLAY INVISIBLE (2735 3285);
FORCEPROP 1 LASTPIN (2725 3275) BN 6
J 0
(2713 3283);
DISPLAY 0.680851 (2713 3283);
PAINT GREEN (2713 3283);
FORCEPROP 2 LAST CDS_LIB standard
J 0
(2775 3275);
PAINT MONO (2775 3275);
DISPLAY INVISIBLE (2775 3275);
FORCEPROP 1 LAST BODY_TYPE PLUMBING
J 0
(2775 3325);
DISPLAY 0.872340 (2775 3325);
PAINT GREEN (2775 3325);
DISPLAY INVISIBLE (2775 3325);
FORCEPROP 1 LAST HDL_TAP TRUE
J 0
(3100 3150);
DISPLAY 0.872340 (3100 3150);
DISPLAY INVISIBLE (3100 3150);
FORCEPROP 1 LAST PATH I86
J 0
(2773 3275);
DISPLAY 0.872340 (2773 3275);
PAINT GREEN (2773 3275);
DISPLAY INVISIBLE (2773 3275);
FORCEADD TAP..1
(2775 3525);
FORCEPROP 3 LASTPIN (2725 3525) SIG_NAME UPI_CPU1_CPU0_P0P1_DP<11>
J 0
(2735 3535);
DISPLAY 0.659574 (2735 3535);
PAINT MONO (2735 3535);
DISPLAY INVISIBLE (2735 3535);
FORCEPROP 1 LASTPIN (2725 3525) BN 11
J 0
(2713 3533);
DISPLAY 0.680851 (2713 3533);
PAINT GREEN (2713 3533);
FORCEPROP 2 LAST CDS_LIB standard
J 0
(2775 3525);
PAINT MONO (2775 3525);
DISPLAY INVISIBLE (2775 3525);
FORCEPROP 1 LAST BODY_TYPE PLUMBING
J 0
(2775 3575);
DISPLAY 0.872340 (2775 3575);
PAINT GREEN (2775 3575);
DISPLAY INVISIBLE (2775 3575);
FORCEPROP 1 LAST HDL_TAP TRUE
J 0
(3100 3400);
DISPLAY 0.872340 (3100 3400);
DISPLAY INVISIBLE (3100 3400);
FORCEPROP 1 LAST PATH I87
J 0
(2773 3525);
DISPLAY 0.872340 (2773 3525);
PAINT GREEN (2773 3525);
DISPLAY INVISIBLE (2773 3525);
FORCEADD TAP..1
(2775 3575);
FORCEPROP 3 LASTPIN (2725 3575) SIG_NAME UPI_CPU1_CPU0_P0P1_DP<12>
J 0
(2735 3585);
DISPLAY 0.659574 (2735 3585);
PAINT MONO (2735 3585);
DISPLAY INVISIBLE (2735 3585);
FORCEPROP 1 LASTPIN (2725 3575) BN 12
J 0
(2713 3583);
DISPLAY 0.680851 (2713 3583);
PAINT GREEN (2713 3583);
FORCEPROP 2 LAST CDS_LIB standard
J 0
(2775 3575);
PAINT MONO (2775 3575);
DISPLAY INVISIBLE (2775 3575);
FORCEPROP 1 LAST BODY_TYPE PLUMBING
J 0
(2775 3625);
DISPLAY 0.872340 (2775 3625);
PAINT GREEN (2775 3625);
DISPLAY INVISIBLE (2775 3625);
FORCEPROP 1 LAST HDL_TAP TRUE
J 0
(3100 3450);
DISPLAY 0.872340 (3100 3450);
DISPLAY INVISIBLE (3100 3450);
FORCEPROP 1 LAST PATH I88
J 0
(2773 3575);
DISPLAY 0.872340 (2773 3575);
PAINT GREEN (2773 3575);
DISPLAY INVISIBLE (2773 3575);
FORCEADD TAP..1
(2775 3625);
FORCEPROP 3 LASTPIN (2725 3625) SIG_NAME UPI_CPU1_CPU0_P0P1_DP<13>
J 0
(2735 3635);
DISPLAY 0.659574 (2735 3635);
PAINT MONO (2735 3635);
DISPLAY INVISIBLE (2735 3635);
FORCEPROP 1 LASTPIN (2725 3625) BN 13
J 0
(2713 3633);
DISPLAY 0.680851 (2713 3633);
PAINT GREEN (2713 3633);
FORCEPROP 2 LAST CDS_LIB standard
J 0
(2775 3625);
PAINT MONO (2775 3625);
DISPLAY INVISIBLE (2775 3625);
FORCEPROP 1 LAST BODY_TYPE PLUMBING
J 0
(2775 3675);
DISPLAY 0.872340 (2775 3675);
PAINT GREEN (2775 3675);
DISPLAY INVISIBLE (2775 3675);
FORCEPROP 1 LAST HDL_TAP TRUE
J 0
(3100 3500);
DISPLAY 0.872340 (3100 3500);
DISPLAY INVISIBLE (3100 3500);
FORCEPROP 1 LAST PATH I89
J 0
(2773 3625);
DISPLAY 0.872340 (2773 3625);
PAINT GREEN (2773 3625);
DISPLAY INVISIBLE (2773 3625);
FORCEADD TAP..1
R 2
(-600 2125);
FORCEPROP 3 LASTPIN (-550 2125) SIG_NAME UPI_CPU0_CPU1_P1P0_DN<8>
J 0
(-540 2135);
DISPLAY 0.659574 (-540 2135);
PAINT MONO (-540 2135);
DISPLAY INVISIBLE (-540 2135);
FORCEPROP 1 LASTPIN (-550 2125) BN 8
J 2
(-538 2133);
DISPLAY 0.680851 (-538 2133);
PAINT GREEN (-538 2133);
FORCEPROP 2 LAST CDS_LIB standard
J 0
(-600 2125);
DISPLAY INVISIBLE (-600 2125);
FORCEPROP 1 LAST BODY_TYPE PLUMBING
J 2
(-600 2175);
DISPLAY 0.872340 (-600 2175);
PAINT GREEN (-600 2175);
DISPLAY INVISIBLE (-600 2175);
FORCEPROP 1 LAST HDL_TAP TRUE
J 2
(-925 2000);
DISPLAY 0.872340 (-925 2000);
DISPLAY INVISIBLE (-925 2000);
FORCEPROP 1 LAST PATH I9
J 2
(-598 2125);
DISPLAY 0.872340 (-598 2125);
PAINT GREEN (-598 2125);
DISPLAY INVISIBLE (-598 2125);
FORCEADD TAP..1
(2775 3725);
FORCEPROP 3 LASTPIN (2725 3725) SIG_NAME UPI_CPU1_CPU0_P0P1_DP<15>
J 0
(2735 3735);
DISPLAY 0.659574 (2735 3735);
PAINT MONO (2735 3735);
DISPLAY INVISIBLE (2735 3735);
FORCEPROP 1 LASTPIN (2725 3725) BN 15
J 0
(2713 3733);
DISPLAY 0.680851 (2713 3733);
PAINT GREEN (2713 3733);
FORCEPROP 2 LAST CDS_LIB standard
J 0
(2775 3725);
PAINT MONO (2775 3725);
DISPLAY INVISIBLE (2775 3725);
FORCEPROP 1 LAST BODY_TYPE PLUMBING
J 0
(2775 3775);
DISPLAY 0.872340 (2775 3775);
PAINT GREEN (2775 3775);
DISPLAY INVISIBLE (2775 3775);
FORCEPROP 1 LAST HDL_TAP TRUE
J 0
(3100 3600);
DISPLAY 0.872340 (3100 3600);
DISPLAY INVISIBLE (3100 3600);
FORCEPROP 1 LAST PATH I90
J 0
(2773 3725);
DISPLAY 0.872340 (2773 3725);
PAINT GREEN (2773 3725);
DISPLAY INVISIBLE (2773 3725);
FORCEADD TAP..1
(2775 3775);
FORCEPROP 3 LASTPIN (2725 3775) SIG_NAME UPI_CPU1_CPU0_P0P1_DP<16>
J 0
(2735 3785);
DISPLAY 0.659574 (2735 3785);
PAINT MONO (2735 3785);
DISPLAY INVISIBLE (2735 3785);
FORCEPROP 1 LASTPIN (2725 3775) BN 16
J 0
(2713 3783);
DISPLAY 0.680851 (2713 3783);
PAINT GREEN (2713 3783);
FORCEPROP 2 LAST CDS_LIB standard
J 0
(2775 3775);
PAINT MONO (2775 3775);
DISPLAY INVISIBLE (2775 3775);
FORCEPROP 1 LAST BODY_TYPE PLUMBING
J 0
(2775 3825);
DISPLAY 0.872340 (2775 3825);
PAINT GREEN (2775 3825);
DISPLAY INVISIBLE (2775 3825);
FORCEPROP 1 LAST HDL_TAP TRUE
J 0
(3100 3650);
DISPLAY 0.872340 (3100 3650);
DISPLAY INVISIBLE (3100 3650);
FORCEPROP 1 LAST PATH I91
J 0
(2773 3775);
DISPLAY 0.872340 (2773 3775);
PAINT GREEN (2773 3775);
DISPLAY INVISIBLE (2773 3775);
FORCEADD TAP..1
(2775 3675);
FORCEPROP 3 LASTPIN (2725 3675) SIG_NAME UPI_CPU1_CPU0_P0P1_DP<14>
J 0
(2735 3685);
DISPLAY 0.659574 (2735 3685);
PAINT MONO (2735 3685);
DISPLAY INVISIBLE (2735 3685);
FORCEPROP 1 LASTPIN (2725 3675) BN 14
J 0
(2713 3683);
DISPLAY 0.680851 (2713 3683);
PAINT GREEN (2713 3683);
FORCEPROP 2 LAST CDS_LIB standard
J 0
(2775 3675);
PAINT MONO (2775 3675);
DISPLAY INVISIBLE (2775 3675);
FORCEPROP 1 LAST BODY_TYPE PLUMBING
J 0
(2775 3725);
DISPLAY 0.872340 (2775 3725);
PAINT GREEN (2775 3725);
DISPLAY INVISIBLE (2775 3725);
FORCEPROP 1 LAST HDL_TAP TRUE
J 0
(3100 3550);
DISPLAY 0.872340 (3100 3550);
DISPLAY INVISIBLE (3100 3550);
FORCEPROP 1 LAST PATH I92
J 0
(2773 3675);
DISPLAY 0.872340 (2773 3675);
PAINT GREEN (2773 3675);
DISPLAY INVISIBLE (2773 3675);
FORCEADD TAP..1
(2775 3975);
FORCEPROP 3 LASTPIN (2725 3975) SIG_NAME UPI_CPU1_CPU0_P0P1_DP<20>
J 0
(2735 3985);
DISPLAY 0.659574 (2735 3985);
PAINT MONO (2735 3985);
DISPLAY INVISIBLE (2735 3985);
FORCEPROP 1 LASTPIN (2725 3975) BN 20
J 0
(2713 3983);
DISPLAY 0.680851 (2713 3983);
PAINT GREEN (2713 3983);
FORCEPROP 2 LAST CDS_LIB standard
J 0
(2775 3975);
DISPLAY INVISIBLE (2775 3975);
FORCEPROP 1 LAST BODY_TYPE PLUMBING
J 0
(2775 4025);
DISPLAY 0.872340 (2775 4025);
PAINT GREEN (2775 4025);
DISPLAY INVISIBLE (2775 4025);
FORCEPROP 1 LAST HDL_TAP TRUE
J 0
(3100 3850);
DISPLAY 0.872340 (3100 3850);
DISPLAY INVISIBLE (3100 3850);
FORCEPROP 1 LAST PATH I93
J 0
(2773 3975);
DISPLAY 0.872340 (2773 3975);
PAINT GREEN (2773 3975);
DISPLAY INVISIBLE (2773 3975);
FORCEADD TAP..1
(2775 3925);
FORCEPROP 3 LASTPIN (2725 3925) SIG_NAME UPI_CPU1_CPU0_P0P1_DP<19>
J 0
(2735 3935);
DISPLAY 0.659574 (2735 3935);
PAINT MONO (2735 3935);
DISPLAY INVISIBLE (2735 3935);
FORCEPROP 1 LASTPIN (2725 3925) BN 19
J 0
(2713 3933);
DISPLAY 0.680851 (2713 3933);
PAINT GREEN (2713 3933);
FORCEPROP 2 LAST CDS_LIB standard
J 0
(2775 3925);
DISPLAY INVISIBLE (2775 3925);
FORCEPROP 1 LAST BODY_TYPE PLUMBING
J 0
(2775 3975);
DISPLAY 0.872340 (2775 3975);
PAINT GREEN (2775 3975);
DISPLAY INVISIBLE (2775 3975);
FORCEPROP 1 LAST HDL_TAP TRUE
J 0
(3100 3800);
DISPLAY 0.872340 (3100 3800);
DISPLAY INVISIBLE (3100 3800);
FORCEPROP 1 LAST PATH I94
J 0
(2773 3925);
DISPLAY 0.872340 (2773 3925);
PAINT GREEN (2773 3925);
DISPLAY INVISIBLE (2773 3925);
FORCEADD TAP..1
(2775 4025);
FORCEPROP 3 LASTPIN (2725 4025) SIG_NAME UPI_CPU1_CPU0_P0P1_DP<21>
J 0
(2735 4035);
DISPLAY 0.659574 (2735 4035);
PAINT MONO (2735 4035);
DISPLAY INVISIBLE (2735 4035);
FORCEPROP 1 LASTPIN (2725 4025) BN 21
J 0
(2713 4033);
DISPLAY 0.680851 (2713 4033);
PAINT GREEN (2713 4033);
FORCEPROP 2 LAST CDS_LIB standard
J 0
(2775 4025);
DISPLAY INVISIBLE (2775 4025);
FORCEPROP 1 LAST BODY_TYPE PLUMBING
J 0
(2775 4075);
DISPLAY 0.872340 (2775 4075);
PAINT GREEN (2775 4075);
DISPLAY INVISIBLE (2775 4075);
FORCEPROP 1 LAST HDL_TAP TRUE
J 0
(3100 3900);
DISPLAY 0.872340 (3100 3900);
DISPLAY INVISIBLE (3100 3900);
FORCEPROP 1 LAST PATH I95
J 0
(2773 4025);
DISPLAY 0.872340 (2773 4025);
PAINT GREEN (2773 4025);
DISPLAY INVISIBLE (2773 4025);
FORCEADD TAP..1
(2775 3875);
FORCEPROP 3 LASTPIN (2725 3875) SIG_NAME UPI_CPU1_CPU0_P0P1_DP<18>
J 0
(2735 3885);
DISPLAY 0.659574 (2735 3885);
PAINT MONO (2735 3885);
DISPLAY INVISIBLE (2735 3885);
FORCEPROP 1 LASTPIN (2725 3875) BN 18
J 0
(2713 3883);
DISPLAY 0.680851 (2713 3883);
PAINT GREEN (2713 3883);
FORCEPROP 2 LAST CDS_LIB standard
J 0
(2775 3875);
DISPLAY INVISIBLE (2775 3875);
FORCEPROP 1 LAST BODY_TYPE PLUMBING
J 0
(2775 3925);
DISPLAY 0.872340 (2775 3925);
PAINT GREEN (2775 3925);
DISPLAY INVISIBLE (2775 3925);
FORCEPROP 1 LAST HDL_TAP TRUE
J 0
(3100 3750);
DISPLAY 0.872340 (3100 3750);
DISPLAY INVISIBLE (3100 3750);
FORCEPROP 1 LAST PATH I96
J 0
(2773 3875);
DISPLAY 0.872340 (2773 3875);
PAINT GREEN (2773 3875);
DISPLAY INVISIBLE (2773 3875);
FORCEADD TAP..1
(2775 3825);
FORCEPROP 3 LASTPIN (2725 3825) SIG_NAME UPI_CPU1_CPU0_P0P1_DP<17>
J 0
(2735 3835);
DISPLAY 0.659574 (2735 3835);
PAINT MONO (2735 3835);
DISPLAY INVISIBLE (2735 3835);
FORCEPROP 1 LASTPIN (2725 3825) BN 17
J 0
(2713 3833);
DISPLAY 0.680851 (2713 3833);
PAINT GREEN (2713 3833);
FORCEPROP 2 LAST CDS_LIB standard
J 0
(2775 3825);
DISPLAY INVISIBLE (2775 3825);
FORCEPROP 1 LAST BODY_TYPE PLUMBING
J 0
(2775 3875);
DISPLAY 0.872340 (2775 3875);
PAINT GREEN (2775 3875);
DISPLAY INVISIBLE (2775 3875);
FORCEPROP 1 LAST HDL_TAP TRUE
J 0
(3100 3700);
DISPLAY 0.872340 (3100 3700);
DISPLAY INVISIBLE (3100 3700);
FORCEPROP 1 LAST PATH I97
J 0
(2773 3825);
DISPLAY 0.872340 (2773 3825);
PAINT GREEN (2773 3825);
DISPLAY INVISIBLE (2773 3825);
FORCEADD TAP..1
(2775 4125);
FORCEPROP 3 LASTPIN (2725 4125) SIG_NAME UPI_CPU1_CPU0_P0P1_DP<23>
J 0
(2735 4135);
DISPLAY 0.659574 (2735 4135);
PAINT MONO (2735 4135);
DISPLAY INVISIBLE (2735 4135);
FORCEPROP 1 LASTPIN (2725 4125) BN 23
J 0
(2713 4133);
DISPLAY 0.680851 (2713 4133);
PAINT GREEN (2713 4133);
FORCEPROP 2 LAST CDS_LIB standard
J 0
(2775 4125);
DISPLAY INVISIBLE (2775 4125);
FORCEPROP 1 LAST BODY_TYPE PLUMBING
J 0
(2775 4175);
DISPLAY 0.872340 (2775 4175);
PAINT GREEN (2775 4175);
DISPLAY INVISIBLE (2775 4175);
FORCEPROP 1 LAST HDL_TAP TRUE
J 0
(3100 4000);
DISPLAY 0.872340 (3100 4000);
DISPLAY INVISIBLE (3100 4000);
FORCEPROP 1 LAST PATH I98
J 0
(2773 4125);
DISPLAY 0.872340 (2773 4125);
PAINT GREEN (2773 4125);
DISPLAY INVISIBLE (2773 4125);
FORCEADD TAP..1
(2775 4075);
FORCEPROP 3 LASTPIN (2725 4075) SIG_NAME UPI_CPU1_CPU0_P0P1_DP<22>
J 0
(2735 4085);
DISPLAY 0.659574 (2735 4085);
PAINT MONO (2735 4085);
DISPLAY INVISIBLE (2735 4085);
FORCEPROP 1 LASTPIN (2725 4075) BN 22
J 0
(2713 4083);
DISPLAY 0.680851 (2713 4083);
PAINT GREEN (2713 4083);
FORCEPROP 2 LAST CDS_LIB standard
J 0
(2775 4075);
DISPLAY INVISIBLE (2775 4075);
FORCEPROP 1 LAST BODY_TYPE PLUMBING
J 0
(2775 4125);
DISPLAY 0.872340 (2775 4125);
PAINT GREEN (2775 4125);
DISPLAY INVISIBLE (2775 4125);
FORCEPROP 1 LAST HDL_TAP TRUE
J 0
(3100 3950);
DISPLAY 0.872340 (3100 3950);
DISPLAY INVISIBLE (3100 3950);
FORCEPROP 1 LAST PATH I99
J 0
(2773 4075);
DISPLAY 0.872340 (2773 4075);
PAINT GREEN (2773 4075);
DISPLAY INVISIBLE (2773 4075);
FORCEADD QUANTA_TITLE_BLOCK_C..1
(5700 -1375);
FORCEPROP 0 LAST CDS_CON_LAST_MODIFIED Fri Aug 25 14:00:45 2023
J 0
(3815 -1360);
PAINT MONO (3815 -1360);
DISPLAY INVISIBLE (3815 -1360);
FORCEPROP 1 LAST CUSTOM_TXT_CDS <CON_LAST_MODIFIED>
J 0
(3815 -1360);
DISPLAY 0.978723 (3815 -1360);
FORCEPROP 2 LAST CUSTOM_TXT_CDS <XR_PAGE_TITLE>
J 0
(-2190 3875);
DISPLAY 0.638298 (-2190 3875);
PAINT PINK (-2190 3875);
DISPLAY INVISIBLE (-2190 3875);
FORCEPROP 2 LAST CUSTOM_TXT_CDS <Q_NUMBER>
J 0
(4297 -1272);
DISPLAY 1.212766 (4297 -1272);
FORCEPROP 1 LAST CUSTOM_TXT_CDS <NAME_2>
J 0
(2525 -1325);
FORCEPROP 1 LAST CUSTOM_TXT_CDS <NAME_1>
J 0
(2525 -1200);
FORCEPROP 1 LAST CUSTOM_TXT_CDS <Q_PROJ>
J 0
(3318 -1273);
DISPLAY 1.212766 (3318 -1273);
FORCEPROP 1 LAST CUSTOM_TXT_CDS <Q_REV>
J 0
(5516 -1272);
DISPLAY 1.212766 (5516 -1272);
FORCEPROP 1 LAST CUSTOM_TXT_CDS <CON_PAGE_NUM> OF <CON_TOTAL_PAGES>
J 0
(5254 -1357);
DISPLAY 0.978723 (5254 -1357);
FORCEPROP 1 LAST Q_TITLE SPR CPU1 - UPI0 (20 OF 30)
J 0
(-3666 -1349);
DISPLAY 1.957447 (-3666 -1349);
PAINT GREEN (-3666 -1349);
FORCEPROP 1 LAST Q_DEPT 
J 1
(1937 -1326);
DISPLAY 1.957447 (1937 -1326);
PAINT GREEN (1937 -1326);
FORCEPROP 1 LAST COMMENT_BODY TRUE
J 0
(5712 -1388);
DISPLAY 0.978723 (5712 -1388);
PAINT GREEN (5712 -1388);
DISPLAY INVISIBLE (5712 -1388);
FORCEPROP 2 LAST CDS_XR_PAGE_TITLE CR-63 : @S9S_MB_2U_LIB.S9S_MB_2U(SCH_1):PAGE63
J 0
(-2190 3875);
DISPLAY 0.638298 (-2190 3875);
PAINT PINK (-2190 3875);
DISPLAY INVISIBLE (-2190 3875);
FORCEPROP 2 LAST CDS_LIB pure_quanta
J 0
(5700 -1375);
PAINT MONO (5700 -1375);
DISPLAY INVISIBLE (5700 -1375);
FORCEPROP 1 LAST CDS_LMAN_SYM_OUTLINE -9475,6775,100,-125
J 0
(5700 -1375);
DISPLAY 0.468085 (5700 -1375);
PAINT GREEN (5700 -1375);
DISPLAY INVISIBLE (5700 -1375);
FORCEPROP 2 LAST PAGE_BORDER TRUE
J 0
(-2190 3875);
DISPLAY 0.638298 (-2190 3875);
PAINT PINK (-2190 3875);
DISPLAY INVISIBLE (-2190 3875);
WIRE 17 -1 (2825 3000)(2825 3050);
WIRE 17 -1 (2825 3050)(2825 3100);
WIRE 17 -1 (2825 3100)(2825 3150);
WIRE 17 -1 (2825 3150)(2825 3200);
WIRE 17 -1 (2825 3200)(2825 3250);
WIRE 17 -1 (2825 3250)(2825 3300);
WIRE 17 -1 (2825 3300)(2825 3350);
WIRE 17 -1 (2825 3350)(2825 3400);
WIRE 17 -1 (2825 3400)(2825 3450);
WIRE 17 -1 (2825 3450)(2825 3500);
WIRE 17 -1 (2825 3500)(2825 3550);
WIRE 17 -1 (2825 3550)(2825 3600);
WIRE 17 -1 (2825 3600)(2825 3650);
WIRE 17 -1 (2825 3650)(2825 3700);
WIRE 17 -1 (2825 3700)(2825 3750);
WIRE 17 -1 (2825 3750)(2825 3800);
WIRE 17 -1 (2825 3800)(2825 3850);
WIRE 17 -1 (2825 3850)(2825 3900);
WIRE 17 -1 (2825 3900)(2825 3950);
WIRE 17 -1 (2825 3950)(2825 4000);
WIRE 17 -1 (2825 4000)(2825 4050);
WIRE 17 -1 (2825 4050)(2825 4100);
WIRE 17 -1 (2825 4100)(2825 4150);
WIRE 17 -1 (2825 4150)(3925 4150);
FORCEPROP 2 LAST SIG_NAME UPI_CPU1_CPU0_P0P1_DP<23:0>
J 0
(2965 4160);
DISPLAY 0.680851 (2965 4160);
PAINT WHITE (2965 4160);
WIRE 17 -1 (2825 1750)(2825 1800);
WIRE 17 -1 (2825 1800)(2825 1850);
WIRE 17 -1 (2825 1850)(2825 1900);
WIRE 17 -1 (2825 1900)(2825 1950);
WIRE 17 -1 (2825 1950)(2825 2000);
WIRE 17 -1 (2825 2000)(2825 2050);
WIRE 17 -1 (2825 2050)(2825 2100);
WIRE 17 -1 (2825 2100)(2825 2150);
WIRE 17 -1 (2825 2200)(2825 2150);
WIRE 17 -1 (2825 2200)(2825 2250);
WIRE 17 -1 (2825 2250)(2825 2300);
WIRE 17 -1 (2825 2300)(2825 2350);
WIRE 17 -1 (2825 2350)(2825 2400);
WIRE 17 -1 (2825 2400)(2825 2450);
WIRE 17 -1 (2825 2450)(2825 2500);
WIRE 17 -1 (2825 2500)(2825 2550);
WIRE 17 -1 (2825 2550)(2825 2600);
WIRE 17 -1 (2825 2600)(2825 2650);
WIRE 17 -1 (2825 2650)(2825 2700);
WIRE 17 -1 (2825 2700)(2825 2750);
WIRE 17 -1 (2825 2750)(2825 2800);
WIRE 17 -1 (2825 2800)(2825 2850);
WIRE 17 -1 (2825 2850)(2825 2900);
WIRE 17 -1 (2825 2900)(3925 2900);
FORCEPROP 2 LAST SIG_NAME UPI_CPU1_CPU0_P0P1_DN<23:0>
J 0
(2965 2910);
DISPLAY 0.680851 (2965 2910);
PAINT WHITE (2965 2910);
WIRE 17 -1 (-650 3000)(-650 3050);
WIRE 17 -1 (-650 3050)(-650 3100);
WIRE 17 -1 (-650 3100)(-650 3150);
WIRE 17 -1 (-650 3150)(-650 3200);
WIRE 17 -1 (-650 3200)(-650 3250);
WIRE 17 -1 (-650 3250)(-650 3300);
WIRE 17 -1 (-650 3300)(-650 3350);
WIRE 17 -1 (-650 3350)(-650 3400);
WIRE 17 -1 (-650 3400)(-650 3450);
WIRE 17 -1 (-650 3450)(-650 3500);
WIRE 17 -1 (-650 3500)(-650 3550);
WIRE 17 -1 (-650 3550)(-650 3600);
WIRE 17 -1 (-650 3600)(-650 3650);
WIRE 17 -1 (-650 3650)(-650 3700);
WIRE 17 -1 (-650 3700)(-650 3750);
WIRE 17 -1 (-650 3750)(-650 3800);
WIRE 17 -1 (-650 3800)(-650 3850);
WIRE 17 -1 (-650 3850)(-650 3900);
WIRE 17 -1 (-650 3900)(-650 3950);
WIRE 17 -1 (-650 3950)(-650 4000);
WIRE 17 -1 (-650 4000)(-650 4050);
WIRE 17 -1 (-650 4050)(-650 4100);
WIRE 17 -1 (-650 4100)(-650 4150);
WIRE 17 -1 (-1800 4150)(-650 4150);
FORCEPROP 2 LAST SIG_NAME UPI_CPU0_CPU1_P1P0_DP<23:0>
J 0
(-1685 4160);
DISPLAY 0.680851 (-1685 4160);
PAINT WHITE (-1685 4160);
WIRE 17 -1 (-650 1750)(-650 1800);
WIRE 17 -1 (-650 1800)(-650 1850);
WIRE 17 -1 (-650 1850)(-650 1900);
WIRE 17 -1 (-650 1900)(-650 1950);
WIRE 17 -1 (-650 1950)(-650 2000);
WIRE 17 -1 (-650 2000)(-650 2050);
WIRE 17 -1 (-650 2050)(-650 2100);
WIRE 17 -1 (-650 2100)(-650 2150);
WIRE 17 -1 (-650 2150)(-650 2200);
WIRE 17 -1 (-650 2200)(-650 2250);
WIRE 17 -1 (-650 2250)(-650 2300);
WIRE 17 -1 (-650 2300)(-650 2350);
WIRE 17 -1 (-650 2350)(-650 2400);
WIRE 17 -1 (-650 2400)(-650 2450);
WIRE 17 -1 (-650 2450)(-650 2500);
WIRE 17 -1 (-650 2500)(-650 2550);
WIRE 17 -1 (-650 2550)(-650 2600);
WIRE 17 -1 (-650 2600)(-650 2650);
WIRE 17 -1 (-650 2650)(-650 2700);
WIRE 17 -1 (-650 2700)(-650 2750);
WIRE 17 -1 (-650 2750)(-650 2800);
WIRE 17 -1 (-650 2800)(-650 2850);
WIRE 17 -1 (-650 2850)(-650 2900);
WIRE 17 -1 (-1800 2900)(-650 2900);
FORCEPROP 2 LAST SIG_NAME UPI_CPU0_CPU1_P1P0_DN<23:0>
J 0
(-1685 2910);
DISPLAY 0.680851 (-1685 2910);
PAINT WHITE (-1685 2910);
WIRE 16 -1 (-550 2875)(-100 2875);
WIRE 16 -1 (-550 2825)(-100 2825);
WIRE 16 -1 (-550 2775)(-100 2775);
WIRE 16 -1 (-550 2725)(-100 2725);
WIRE 16 -1 (-550 2675)(-100 2675);
WIRE 16 -1 (-550 2625)(-100 2625);
WIRE 16 -1 (-550 2575)(-100 2575);
WIRE 16 -1 (-550 2525)(-100 2525);
WIRE 16 -1 (-550 2475)(-100 2475);
WIRE 16 -1 (-550 2425)(-100 2425);
WIRE 16 -1 (-550 2375)(-100 2375);
WIRE 16 -1 (-550 2325)(-100 2325);
WIRE 16 -1 (-550 2275)(-100 2275);
WIRE 16 -1 (-550 2225)(-100 2225);
WIRE 16 -1 (-550 2175)(-100 2175);
WIRE 16 -1 (-550 2125)(-100 2125);
WIRE 16 -1 (-550 2075)(-100 2075);
WIRE 16 -1 (-550 2025)(-100 2025);
WIRE 16 -1 (-550 1975)(-100 1975);
WIRE 16 -1 (-550 1925)(-100 1925);
WIRE 16 -1 (-550 1875)(-100 1875);
WIRE 16 -1 (-550 1825)(-100 1825);
WIRE 16 -1 (-550 1775)(-100 1775);
WIRE 16 -1 (-550 1725)(-100 1725);
WIRE 16 -1 (-550 4125)(-100 4125);
WIRE 16 -1 (-550 4075)(-100 4075);
WIRE 16 -1 (-550 4025)(-100 4025);
WIRE 16 -1 (-550 3975)(-100 3975);
WIRE 16 -1 (-550 3925)(-100 3925);
WIRE 16 -1 (-550 3875)(-100 3875);
WIRE 16 -1 (-550 3825)(-100 3825);
WIRE 16 -1 (-550 3775)(-100 3775);
WIRE 16 -1 (-550 3725)(-100 3725);
WIRE 16 -1 (-550 3675)(-100 3675);
WIRE 16 -1 (-550 3625)(-100 3625);
WIRE 16 -1 (-550 3575)(-100 3575);
WIRE 16 -1 (-550 3525)(-100 3525);
WIRE 16 -1 (-550 3475)(-100 3475);
WIRE 16 -1 (-550 3425)(-100 3425);
WIRE 16 -1 (-550 3375)(-100 3375);
WIRE 16 -1 (-550 3325)(-100 3325);
WIRE 16 -1 (-550 3275)(-100 3275);
WIRE 16 -1 (-550 3225)(-100 3225);
WIRE 16 -1 (-550 3175)(-100 3175);
WIRE 16 -1 (-550 3125)(-100 3125);
WIRE 16 -1 (-550 3075)(-100 3075);
WIRE 16 -1 (-550 3025)(-100 3025);
WIRE 16 -1 (-550 2975)(-100 2975);
WIRE 16 -1 (2300 2875)(2725 2875);
WIRE 16 -1 (2300 2825)(2725 2825);
WIRE 16 -1 (2300 2775)(2725 2775);
WIRE 16 -1 (2300 2725)(2725 2725);
WIRE 16 -1 (2300 2675)(2725 2675);
WIRE 16 -1 (2300 2625)(2725 2625);
WIRE 16 -1 (2300 2575)(2725 2575);
WIRE 16 -1 (2300 2525)(2725 2525);
WIRE 16 -1 (2300 2475)(2725 2475);
WIRE 16 -1 (2300 2425)(2725 2425);
WIRE 16 -1 (2300 2375)(2725 2375);
WIRE 16 -1 (2300 2325)(2725 2325);
WIRE 16 -1 (2300 2275)(2725 2275);
WIRE 16 -1 (2300 2225)(2725 2225);
WIRE 16 -1 (2300 2175)(2725 2175);
WIRE 16 -1 (2300 2125)(2725 2125);
WIRE 16 -1 (2300 2075)(2725 2075);
WIRE 16 -1 (2300 2025)(2725 2025);
WIRE 16 -1 (2300 1975)(2725 1975);
WIRE 16 -1 (2300 1925)(2725 1925);
WIRE 16 -1 (2300 1875)(2725 1875);
WIRE 16 -1 (2300 1825)(2725 1825);
WIRE 16 -1 (2300 1775)(2725 1775);
WIRE 16 -1 (2300 1725)(2725 1725);
WIRE 16 -1 (2300 4125)(2725 4125);
WIRE 16 -1 (2300 4075)(2725 4075);
WIRE 16 -1 (2300 4025)(2725 4025);
WIRE 16 -1 (2300 3975)(2725 3975);
WIRE 16 -1 (2300 3925)(2725 3925);
WIRE 16 -1 (2300 3875)(2725 3875);
WIRE 16 -1 (2300 3825)(2725 3825);
WIRE 16 -1 (2300 3775)(2725 3775);
WIRE 16 -1 (2300 3725)(2725 3725);
WIRE 16 -1 (2300 3675)(2725 3675);
WIRE 16 -1 (2300 3625)(2725 3625);
WIRE 16 -1 (2300 3575)(2725 3575);
WIRE 16 -1 (2300 3525)(2725 3525);
WIRE 16 -1 (2300 3475)(2725 3475);
WIRE 16 -1 (2300 3425)(2725 3425);
WIRE 16 -1 (2300 3375)(2725 3375);
WIRE 16 -1 (2300 3325)(2725 3325);
WIRE 16 -1 (2300 3275)(2725 3275);
WIRE 16 -1 (2300 3225)(2725 3225);
WIRE 16 -1 (2300 3175)(2725 3175);
WIRE 16 -1 (2300 3125)(2725 3125);
WIRE 16 -1 (2300 3075)(2725 3075);
WIRE 16 -1 (2300 3025)(2725 3025);
WIRE 16 -1 (2300 2975)(2725 2975);
QUIT
